FILE_TYPE = MACRO_DRAWING;
SET COLOR_WIRE YELLOW;
SET COLOR_PROP ORANGE;
SET COLOR_DOT WHITE;
SET COLOR_ARC YELLOW;
SET COLOR_BODY GREEN;
SET COLOR_NOTE PURPLE;
SET PROP_DISPLAY VALUE;
SET PAGE_NUMBER P86;
FORCEADD GND..1
(-2125 1825);
FORCEPROP 3 LASTPIN (-2125 1875) SIG_NAME GND\g
J 0
(-2115 1885);
DISPLAY 0.659574 (-2115 1885);
PAINT MONO (-2115 1885);
DISPLAY INVISIBLE (-2115 1885);
FORCEPROP 1 LAST SIZE 1B
J 0
(-2050 1775);
DISPLAY 0.851064 (-2050 1775);
PAINT GREEN (-2050 1775);
DISPLAY INVISIBLE (-2050 1775);
FORCEPROP 2 LAST CDS_LIB mstr_symbols
J 0
(-2125 1825);
DISPLAY 0.723404 (-2125 1825);
DISPLAY INVISIBLE (-2125 1825);
FORCEPROP 1 LAST BODY_TYPE PLUMBING
J 0
(-2170 1782);
DISPLAY 0.340426 (-2170 1782);
PAINT GREEN (-2170 1782);
DISPLAY INVISIBLE (-2170 1782);
FORCEPROP 1 LAST PATH I150
J 0
(-2050 1825);
DISPLAY 0.872340 (-2050 1825);
PAINT GREEN (-2050 1825);
DISPLAY INVISIBLE (-2050 1825);
FORCEPROP 1 LAST VOLTAGE 0.0
J 0
(-2170 1782);
DISPLAY 0.723404 (-2170 1782);
PAINT SKYBLUE (-2170 1782);
DISPLAY INVISIBLE (-2170 1782);
FORCEPROP 1 LAST HDL_POWER GND
J 0
(-2125 1975);
DISPLAY 0.851064 (-2125 1975);
PAINT GREEN (-2125 1975);
DISPLAY INVISIBLE (-2125 1975);
FORCEADD GND..1
(-325 1650);
FORCEPROP 3 LASTPIN (-325 1700) SIG_NAME GND\g
J 0
(-315 1710);
DISPLAY 0.659574 (-315 1710);
PAINT MONO (-315 1710);
DISPLAY INVISIBLE (-315 1710);
FORCEPROP 1 LAST SIZE 1B
J 0
(-250 1600);
DISPLAY 0.851064 (-250 1600);
PAINT GREEN (-250 1600);
DISPLAY INVISIBLE (-250 1600);
FORCEPROP 2 LAST CDS_LIB mstr_symbols
J 0
(-325 1650);
DISPLAY 0.723404 (-325 1650);
DISPLAY INVISIBLE (-325 1650);
FORCEPROP 1 LAST BODY_TYPE PLUMBING
J 0
(-370 1607);
DISPLAY 0.340426 (-370 1607);
PAINT GREEN (-370 1607);
DISPLAY INVISIBLE (-370 1607);
FORCEPROP 1 LAST PATH I152
J 0
(-250 1650);
DISPLAY 0.872340 (-250 1650);
PAINT GREEN (-250 1650);
DISPLAY INVISIBLE (-250 1650);
FORCEPROP 1 LAST VOLTAGE 0.0
J 0
(-370 1607);
DISPLAY 0.723404 (-370 1607);
PAINT SKYBLUE (-370 1607);
DISPLAY INVISIBLE (-370 1607);
FORCEPROP 1 LAST HDL_POWER GND
J 0
(-325 1800);
DISPLAY 0.851064 (-325 1800);
PAINT GREEN (-325 1800);
DISPLAY INVISIBLE (-325 1800);
FORCEADD OFFPAGE..5
(-8550 2075);
FORCEPROP 2 LAST $XR0 11 
J 0
(-8774 2075);
DISPLAY 0.638298 (-8774 2075);
PAINT MONO (-8774 2075);
FORCEPROP 2 LAST PATH I167
J 0
(-8500 2150);
DISPLAY 0.808511 (-8500 2150);
DISPLAY INVISIBLE (-8500 2150);
FORCEPROP 1 LAST COMMENT_BODY TRUE
J 0
(-8450 2000);
DISPLAY 0.872340 (-8450 2000);
PAINT GREEN (-8450 2000);
DISPLAY INVISIBLE (-8450 2000);
FORCEPROP 1 LAST OFFPAGE TRUE
J 0
(-8225 1950);
DISPLAY 0.872340 (-8225 1950);
PAINT GREEN (-8225 1950);
DISPLAY INVISIBLE (-8225 1950);
FORCEPROP 2 LAST CDS_LIB mstr_standard
J 0
(-8550 2075);
DISPLAY 0.808511 (-8550 2075);
DISPLAY INVISIBLE (-8550 2075);
FORCEADD OFFPAGE..5
(-8550 2125);
FORCEPROP 2 LAST $XR0 11 
J 0
(-8774 2125);
DISPLAY 0.638298 (-8774 2125);
PAINT MONO (-8774 2125);
FORCEPROP 2 LAST PATH I168
J 0
(-8500 2200);
DISPLAY 0.808511 (-8500 2200);
DISPLAY INVISIBLE (-8500 2200);
FORCEPROP 1 LAST COMMENT_BODY TRUE
J 0
(-8450 2050);
DISPLAY 0.872340 (-8450 2050);
PAINT GREEN (-8450 2050);
DISPLAY INVISIBLE (-8450 2050);
FORCEPROP 1 LAST OFFPAGE TRUE
J 0
(-8225 2000);
DISPLAY 0.872340 (-8225 2000);
PAINT GREEN (-8225 2000);
DISPLAY INVISIBLE (-8225 2000);
FORCEPROP 2 LAST CDS_LIB mstr_standard
J 0
(-8550 2125);
DISPLAY 0.808511 (-8550 2125);
DISPLAY INVISIBLE (-8550 2125);
FORCEADD OFFPAGE..6
(-8550 3725);
FORCEPROP 2 LAST $XR0 11 
J 0
(-8799 3725);
DISPLAY 0.638298 (-8799 3725);
PAINT MONO (-8799 3725);
FORCEPROP 2 LAST PATH I174
J 0
(-8500 3800);
DISPLAY 0.808511 (-8500 3800);
DISPLAY INVISIBLE (-8500 3800);
FORCEPROP 1 LAST COMMENT_BODY TRUE
J 0
(-8450 3650);
DISPLAY 0.872340 (-8450 3650);
PAINT GREEN (-8450 3650);
DISPLAY INVISIBLE (-8450 3650);
FORCEPROP 1 LAST OFFPAGE TRUE
J 0
(-8225 3600);
DISPLAY 0.872340 (-8225 3600);
PAINT GREEN (-8225 3600);
DISPLAY INVISIBLE (-8225 3600);
FORCEPROP 2 LAST CDS_LIB mstr_standard
J 0
(-8550 3725);
DISPLAY 0.723404 (-8550 3725);
PAINT MONO (-8550 3725);
DISPLAY INVISIBLE (-8550 3725);
FORCEADD OFFPAGE..1
(-8525 3225);
FORCEPROP 2 LAST $XR0 11 
J 0
(-8746 3225);
DISPLAY 0.638298 (-8746 3225);
PAINT MONO (-8746 3225);
FORCEPROP 2 LAST PATH I176
J 0
(-8725 3450);
DISPLAY 0.808511 (-8725 3450);
DISPLAY INVISIBLE (-8725 3450);
FORCEPROP 1 LAST COMMENT_BODY TRUE
J 0
(-8400 3125);
DISPLAY 0.872340 (-8400 3125);
PAINT GREEN (-8400 3125);
DISPLAY INVISIBLE (-8400 3125);
FORCEPROP 1 LAST OFFPAGE TRUE
J 0
(-8200 3100);
DISPLAY 0.872340 (-8200 3100);
PAINT GREEN (-8200 3100);
DISPLAY INVISIBLE (-8200 3100);
FORCEPROP 2 LAST CDS_LIB mstr_standard
J 0
(-8525 3225);
DISPLAY 0.808511 (-8525 3225);
DISPLAY INVISIBLE (-8525 3225);
FORCEADD VCC_CORE..1
(-8925 3575);
FORCEPROP 3 LASTPIN (-8925 3525) SIG_NAME P3V3_STBY\g
J 0
(-8915 3535);
DISPLAY 0.659574 (-8915 3535);
PAINT MONO (-8915 3535);
DISPLAY INVISIBLE (-8915 3535);
FORCEPROP 1 LAST HDL_POWER P3V3_STBY
J 1
(-8925 3625);
DISPLAY 0.489362 (-8925 3625);
PAINT GREEN (-8925 3625);
FORCEPROP 2 LAST CDS_LIB mstr_symbols
J 0
(-8925 3575);
PAINT MONO (-8925 3575);
DISPLAY INVISIBLE (-8925 3575);
FORCEPROP 1 LAST PATH I177
J 0
(-8875 3600);
DISPLAY 0.872340 (-8875 3600);
PAINT GREEN (-8875 3600);
DISPLAY INVISIBLE (-8875 3600);
FORCEPROP 0 LAST VOLTAGE 3.3
J 0
(-9200 3725);
DISPLAY 1.021277 (-9200 3725);
PAINT SKYBLUE (-9200 3725);
DISPLAY INVISIBLE (-9200 3725);
FORCEPROP 2 LAST ROOM PVCCINFAON_CPU0_CTRL
J 0
(-8925 3675);
DISPLAY 0.808511 (-8925 3675);
PAINT RED (-8925 3675);
DISPLAY INVISIBLE (-8925 3675);
FORCEADD OFFPAGE..1
(-8550 4225);
FORCEPROP 2 LAST $XR0 11 
J 0
(-8771 4225);
DISPLAY 0.638298 (-8771 4225);
PAINT MONO (-8771 4225);
FORCEPROP 2 LAST PATH I178
J 0
(-8500 4300);
DISPLAY 0.808511 (-8500 4300);
DISPLAY INVISIBLE (-8500 4300);
FORCEPROP 1 LAST COMMENT_BODY TRUE
J 0
(-8425 4125);
DISPLAY 0.872340 (-8425 4125);
PAINT GREEN (-8425 4125);
DISPLAY INVISIBLE (-8425 4125);
FORCEPROP 1 LAST OFFPAGE TRUE
J 0
(-8225 4100);
DISPLAY 0.872340 (-8225 4100);
PAINT GREEN (-8225 4100);
DISPLAY INVISIBLE (-8225 4100);
FORCEPROP 2 LAST CDS_LIB mstr_standard
J 0
(-8550 4225);
DISPLAY 0.808511 (-8550 4225);
DISPLAY INVISIBLE (-8550 4225);
FORCEADD OFFPAGE..6
(-8550 4175);
FORCEPROP 2 LAST $XR0 11 
J 0
(-8799 4175);
DISPLAY 0.638298 (-8799 4175);
PAINT MONO (-8799 4175);
FORCEPROP 2 LAST PATH I179
J 0
(-8500 4250);
DISPLAY 0.808511 (-8500 4250);
DISPLAY INVISIBLE (-8500 4250);
FORCEPROP 1 LAST COMMENT_BODY TRUE
J 0
(-8450 4100);
DISPLAY 0.872340 (-8450 4100);
PAINT GREEN (-8450 4100);
DISPLAY INVISIBLE (-8450 4100);
FORCEPROP 1 LAST OFFPAGE TRUE
J 0
(-8225 4050);
DISPLAY 0.872340 (-8225 4050);
PAINT GREEN (-8225 4050);
DISPLAY INVISIBLE (-8225 4050);
FORCEPROP 2 LAST CDS_LIB mstr_standard
J 0
(-8550 4175);
DISPLAY 0.723404 (-8550 4175);
PAINT MONO (-8550 4175);
DISPLAY INVISIBLE (-8550 4175);
FORCEADD OFFPAGE..1
(-8550 4275);
FORCEPROP 2 LAST $XR0 11 
J 0
(-8771 4275);
DISPLAY 0.638298 (-8771 4275);
PAINT MONO (-8771 4275);
FORCEPROP 2 LAST PATH I180
J 0
(-8500 4350);
DISPLAY 0.808511 (-8500 4350);
DISPLAY INVISIBLE (-8500 4350);
FORCEPROP 1 LAST COMMENT_BODY TRUE
J 0
(-8425 4175);
DISPLAY 0.872340 (-8425 4175);
PAINT GREEN (-8425 4175);
DISPLAY INVISIBLE (-8425 4175);
FORCEPROP 1 LAST OFFPAGE TRUE
J 0
(-8225 4150);
DISPLAY 0.872340 (-8225 4150);
PAINT GREEN (-8225 4150);
DISPLAY INVISIBLE (-8225 4150);
FORCEPROP 2 LAST CDS_LIB mstr_standard
J 0
(-8550 4275);
DISPLAY 0.723404 (-8550 4275);
PAINT MONO (-8550 4275);
DISPLAY INVISIBLE (-8550 4275);
FORCEADD OFFPAGE..1
(-8550 4375);
FORCEPROP 2 LAST $XR0 11 
J 0
(-8771 4375);
DISPLAY 0.638298 (-8771 4375);
PAINT MONO (-8771 4375);
FORCEPROP 2 LAST PATH I181
J 0
(-8500 4450);
DISPLAY 0.808511 (-8500 4450);
DISPLAY INVISIBLE (-8500 4450);
FORCEPROP 1 LAST COMMENT_BODY TRUE
J 0
(-8425 4275);
DISPLAY 0.872340 (-8425 4275);
PAINT GREEN (-8425 4275);
DISPLAY INVISIBLE (-8425 4275);
FORCEPROP 1 LAST OFFPAGE TRUE
J 0
(-8225 4250);
DISPLAY 0.872340 (-8225 4250);
PAINT GREEN (-8225 4250);
DISPLAY INVISIBLE (-8225 4250);
FORCEPROP 2 LAST CDS_LIB mstr_standard
J 0
(-8550 4375);
DISPLAY 0.808511 (-8550 4375);
DISPLAY INVISIBLE (-8550 4375);
FORCEADD OFFPAGE..1
(-8550 4425);
FORCEPROP 2 LAST $XR0 11 
J 0
(-8771 4425);
DISPLAY 0.638298 (-8771 4425);
PAINT MONO (-8771 4425);
FORCEPROP 2 LAST PATH I182
J 0
(-8500 4500);
DISPLAY 0.808511 (-8500 4500);
DISPLAY INVISIBLE (-8500 4500);
FORCEPROP 1 LAST COMMENT_BODY TRUE
J 0
(-8425 4325);
DISPLAY 0.872340 (-8425 4325);
PAINT GREEN (-8425 4325);
DISPLAY INVISIBLE (-8425 4325);
FORCEPROP 1 LAST OFFPAGE TRUE
J 0
(-8225 4300);
DISPLAY 0.872340 (-8225 4300);
PAINT GREEN (-8225 4300);
DISPLAY INVISIBLE (-8225 4300);
FORCEPROP 2 LAST CDS_LIB mstr_standard
J 0
(-8550 4425);
DISPLAY 0.723404 (-8550 4425);
PAINT MONO (-8550 4425);
DISPLAY INVISIBLE (-8550 4425);
FORCEADD OFFPAGE..1
(-8550 4525);
FORCEPROP 2 LAST $XR0 11 
J 0
(-8771 4525);
DISPLAY 0.638298 (-8771 4525);
PAINT MONO (-8771 4525);
FORCEPROP 2 LAST PATH I183
J 0
(-8500 4600);
DISPLAY 0.808511 (-8500 4600);
DISPLAY INVISIBLE (-8500 4600);
FORCEPROP 1 LAST COMMENT_BODY TRUE
J 0
(-8425 4425);
DISPLAY 0.872340 (-8425 4425);
PAINT GREEN (-8425 4425);
DISPLAY INVISIBLE (-8425 4425);
FORCEPROP 1 LAST OFFPAGE TRUE
J 0
(-8225 4400);
DISPLAY 0.872340 (-8225 4400);
PAINT GREEN (-8225 4400);
DISPLAY INVISIBLE (-8225 4400);
FORCEPROP 2 LAST CDS_LIB mstr_standard
J 0
(-8550 4525);
DISPLAY 0.808511 (-8550 4525);
DISPLAY INVISIBLE (-8550 4525);
FORCEADD OFFPAGE..1
(-8550 4575);
FORCEPROP 2 LAST $XR0 11 
J 0
(-8771 4575);
DISPLAY 0.638298 (-8771 4575);
PAINT MONO (-8771 4575);
FORCEPROP 2 LAST PATH I184
J 0
(-8500 4650);
DISPLAY 0.808511 (-8500 4650);
DISPLAY INVISIBLE (-8500 4650);
FORCEPROP 1 LAST COMMENT_BODY TRUE
J 0
(-8425 4475);
DISPLAY 0.872340 (-8425 4475);
PAINT GREEN (-8425 4475);
DISPLAY INVISIBLE (-8425 4475);
FORCEPROP 1 LAST OFFPAGE TRUE
J 0
(-8225 4450);
DISPLAY 0.872340 (-8225 4450);
PAINT GREEN (-8225 4450);
DISPLAY INVISIBLE (-8225 4450);
FORCEPROP 2 LAST CDS_LIB mstr_standard
J 0
(-8550 4575);
DISPLAY 0.723404 (-8550 4575);
PAINT MONO (-8550 4575);
DISPLAY INVISIBLE (-8550 4575);
FORCEADD OFFPAGE..1
(-8550 4725);
FORCEPROP 2 LAST $XR0 11 
J 0
(-8771 4725);
DISPLAY 0.638298 (-8771 4725);
PAINT MONO (-8771 4725);
FORCEPROP 2 LAST PATH I185
J 0
(-8500 4800);
DISPLAY 0.808511 (-8500 4800);
DISPLAY INVISIBLE (-8500 4800);
FORCEPROP 1 LAST COMMENT_BODY TRUE
J 0
(-8425 4625);
DISPLAY 0.872340 (-8425 4625);
PAINT GREEN (-8425 4625);
DISPLAY INVISIBLE (-8425 4625);
FORCEPROP 1 LAST OFFPAGE TRUE
J 0
(-8225 4600);
DISPLAY 0.872340 (-8225 4600);
PAINT GREEN (-8225 4600);
DISPLAY INVISIBLE (-8225 4600);
FORCEPROP 2 LAST CDS_LIB mstr_standard
J 0
(-8550 4725);
DISPLAY 0.723404 (-8550 4725);
PAINT MONO (-8550 4725);
DISPLAY INVISIBLE (-8550 4725);
FORCEADD OFFPAGE..1
(-8550 4675);
FORCEPROP 2 LAST $XR0 11 
J 0
(-8771 4675);
DISPLAY 0.638298 (-8771 4675);
PAINT MONO (-8771 4675);
FORCEPROP 2 LAST PATH I186
J 0
(-8500 4750);
DISPLAY 0.808511 (-8500 4750);
DISPLAY INVISIBLE (-8500 4750);
FORCEPROP 1 LAST COMMENT_BODY TRUE
J 0
(-8425 4575);
DISPLAY 0.872340 (-8425 4575);
PAINT GREEN (-8425 4575);
DISPLAY INVISIBLE (-8425 4575);
FORCEPROP 1 LAST OFFPAGE TRUE
J 0
(-8225 4550);
DISPLAY 0.872340 (-8225 4550);
PAINT GREEN (-8225 4550);
DISPLAY INVISIBLE (-8225 4550);
FORCEPROP 2 LAST CDS_LIB mstr_standard
J 0
(-8550 4675);
DISPLAY 0.808511 (-8550 4675);
DISPLAY INVISIBLE (-8550 4675);
FORCEADD TAP..1
R 2
(-7950 3375);
FORCEPROP 3 LASTPIN (-7900 3375) SIG_NAME M_B_CPU0_SB_CB<1>
J 0
(-7890 3385);
DISPLAY 0.659574 (-7890 3385);
PAINT MONO (-7890 3385);
DISPLAY INVISIBLE (-7890 3385);
FORCEPROP 1 LASTPIN (-7900 3375) BN 1
J 2
(-7888 3383);
DISPLAY 0.489362 (-7888 3383);
PAINT GREEN (-7888 3383);
FORCEPROP 2 LAST CDS_LIB mstr_standard
J 0
(-7950 3375);
DISPLAY 0.723404 (-7950 3375);
PAINT MONO (-7950 3375);
DISPLAY INVISIBLE (-7950 3375);
FORCEPROP 1 LAST BODY_TYPE PLUMBING
J 2
(-7950 3425);
DISPLAY 0.872340 (-7950 3425);
PAINT GREEN (-7950 3425);
DISPLAY INVISIBLE (-7950 3425);
FORCEPROP 1 LAST HDL_TAP TRUE
J 2
(-8275 3250);
DISPLAY 0.872340 (-8275 3250);
DISPLAY INVISIBLE (-8275 3250);
FORCEPROP 1 LAST PATH I187
J 2
(-7948 3375);
DISPLAY 0.872340 (-7948 3375);
PAINT GREEN (-7948 3375);
DISPLAY INVISIBLE (-7948 3375);
FORCEADD TAP..1
R 2
(-7950 3425);
FORCEPROP 3 LASTPIN (-7900 3425) SIG_NAME M_B_CPU0_SB_CB<2>
J 0
(-7890 3435);
DISPLAY 0.659574 (-7890 3435);
PAINT MONO (-7890 3435);
DISPLAY INVISIBLE (-7890 3435);
FORCEPROP 1 LASTPIN (-7900 3425) BN 2
J 2
(-7888 3433);
DISPLAY 0.489362 (-7888 3433);
PAINT GREEN (-7888 3433);
FORCEPROP 2 LAST CDS_LIB mstr_standard
J 0
(-7950 3425);
DISPLAY 0.723404 (-7950 3425);
PAINT MONO (-7950 3425);
DISPLAY INVISIBLE (-7950 3425);
FORCEPROP 1 LAST BODY_TYPE PLUMBING
J 2
(-7950 3475);
DISPLAY 0.872340 (-7950 3475);
PAINT GREEN (-7950 3475);
DISPLAY INVISIBLE (-7950 3475);
FORCEPROP 1 LAST HDL_TAP TRUE
J 2
(-8275 3300);
DISPLAY 0.872340 (-8275 3300);
DISPLAY INVISIBLE (-8275 3300);
FORCEPROP 1 LAST PATH I188
J 2
(-7948 3425);
DISPLAY 0.872340 (-7948 3425);
PAINT GREEN (-7948 3425);
DISPLAY INVISIBLE (-7948 3425);
FORCEADD TAP..1
R 2
(-7950 3325);
FORCEPROP 3 LASTPIN (-7900 3325) SIG_NAME M_B_CPU0_SB_CB<0>
J 0
(-7890 3335);
DISPLAY 0.659574 (-7890 3335);
PAINT MONO (-7890 3335);
DISPLAY INVISIBLE (-7890 3335);
FORCEPROP 1 LASTPIN (-7900 3325) BN 0
J 2
(-7888 3333);
DISPLAY 0.489362 (-7888 3333);
PAINT GREEN (-7888 3333);
FORCEPROP 2 LAST CDS_LIB mstr_standard
J 0
(-7950 3325);
DISPLAY 0.723404 (-7950 3325);
PAINT MONO (-7950 3325);
DISPLAY INVISIBLE (-7950 3325);
FORCEPROP 1 LAST BODY_TYPE PLUMBING
J 2
(-7950 3375);
DISPLAY 0.872340 (-7950 3375);
PAINT GREEN (-7950 3375);
DISPLAY INVISIBLE (-7950 3375);
FORCEPROP 1 LAST HDL_TAP TRUE
J 2
(-8275 3200);
DISPLAY 0.872340 (-8275 3200);
DISPLAY INVISIBLE (-8275 3200);
FORCEPROP 1 LAST PATH I189
J 2
(-7948 3325);
DISPLAY 0.872340 (-7948 3325);
PAINT GREEN (-7948 3325);
DISPLAY INVISIBLE (-7948 3325);
FORCEADD TAP..1
R 2
(-7950 3475);
FORCEPROP 3 LASTPIN (-7900 3475) SIG_NAME M_B_CPU0_SB_CB<3>
J 0
(-7890 3485);
DISPLAY 0.659574 (-7890 3485);
PAINT MONO (-7890 3485);
DISPLAY INVISIBLE (-7890 3485);
FORCEPROP 1 LASTPIN (-7900 3475) BN 3
J 2
(-7888 3483);
DISPLAY 0.489362 (-7888 3483);
PAINT GREEN (-7888 3483);
FORCEPROP 2 LAST CDS_LIB mstr_standard
J 0
(-7950 3475);
DISPLAY 0.723404 (-7950 3475);
PAINT MONO (-7950 3475);
DISPLAY INVISIBLE (-7950 3475);
FORCEPROP 1 LAST BODY_TYPE PLUMBING
J 2
(-7950 3525);
DISPLAY 0.872340 (-7950 3525);
PAINT GREEN (-7950 3525);
DISPLAY INVISIBLE (-7950 3525);
FORCEPROP 1 LAST HDL_TAP TRUE
J 2
(-8275 3350);
DISPLAY 0.872340 (-8275 3350);
DISPLAY INVISIBLE (-8275 3350);
FORCEPROP 1 LAST PATH I190
J 2
(-7948 3475);
DISPLAY 0.872340 (-7948 3475);
PAINT GREEN (-7948 3475);
DISPLAY INVISIBLE (-7948 3475);
FORCEADD TAP..1
R 2
(-7950 3525);
FORCEPROP 3 LASTPIN (-7900 3525) SIG_NAME M_B_CPU0_SB_CB<4>
J 0
(-7890 3535);
DISPLAY 0.659574 (-7890 3535);
PAINT MONO (-7890 3535);
DISPLAY INVISIBLE (-7890 3535);
FORCEPROP 1 LASTPIN (-7900 3525) BN 4
J 2
(-7888 3533);
DISPLAY 0.489362 (-7888 3533);
PAINT GREEN (-7888 3533);
FORCEPROP 2 LAST CDS_LIB mstr_standard
J 0
(-7950 3525);
DISPLAY 0.723404 (-7950 3525);
PAINT MONO (-7950 3525);
DISPLAY INVISIBLE (-7950 3525);
FORCEPROP 1 LAST BODY_TYPE PLUMBING
J 2
(-7950 3575);
DISPLAY 0.872340 (-7950 3575);
PAINT GREEN (-7950 3575);
DISPLAY INVISIBLE (-7950 3575);
FORCEPROP 1 LAST HDL_TAP TRUE
J 2
(-8275 3400);
DISPLAY 0.872340 (-8275 3400);
DISPLAY INVISIBLE (-8275 3400);
FORCEPROP 1 LAST PATH I191
J 2
(-7948 3525);
DISPLAY 0.872340 (-7948 3525);
PAINT GREEN (-7948 3525);
DISPLAY INVISIBLE (-7948 3525);
FORCEADD TAP..1
R 2
(-7950 3575);
FORCEPROP 3 LASTPIN (-7900 3575) SIG_NAME M_B_CPU0_SB_CB<5>
J 0
(-7890 3585);
DISPLAY 0.659574 (-7890 3585);
PAINT MONO (-7890 3585);
DISPLAY INVISIBLE (-7890 3585);
FORCEPROP 1 LASTPIN (-7900 3575) BN 5
J 2
(-7888 3583);
DISPLAY 0.489362 (-7888 3583);
PAINT GREEN (-7888 3583);
FORCEPROP 2 LAST CDS_LIB mstr_standard
J 0
(-7950 3575);
DISPLAY 0.723404 (-7950 3575);
PAINT MONO (-7950 3575);
DISPLAY INVISIBLE (-7950 3575);
FORCEPROP 1 LAST BODY_TYPE PLUMBING
J 2
(-7950 3625);
DISPLAY 0.872340 (-7950 3625);
PAINT GREEN (-7950 3625);
DISPLAY INVISIBLE (-7950 3625);
FORCEPROP 1 LAST HDL_TAP TRUE
J 2
(-8275 3450);
DISPLAY 0.872340 (-8275 3450);
DISPLAY INVISIBLE (-8275 3450);
FORCEPROP 1 LAST PATH I192
J 2
(-7948 3575);
DISPLAY 0.872340 (-7948 3575);
PAINT GREEN (-7948 3575);
DISPLAY INVISIBLE (-7948 3575);
FORCEADD TAP..1
R 2
(-7950 3675);
FORCEPROP 3 LASTPIN (-7900 3675) SIG_NAME M_B_CPU0_SB_CB<7>
J 0
(-7890 3685);
DISPLAY 0.659574 (-7890 3685);
PAINT MONO (-7890 3685);
DISPLAY INVISIBLE (-7890 3685);
FORCEPROP 1 LASTPIN (-7900 3675) BN 7
J 2
(-7888 3683);
DISPLAY 0.489362 (-7888 3683);
PAINT GREEN (-7888 3683);
FORCEPROP 2 LAST CDS_LIB mstr_standard
J 0
(-7950 3675);
DISPLAY 0.723404 (-7950 3675);
PAINT MONO (-7950 3675);
DISPLAY INVISIBLE (-7950 3675);
FORCEPROP 1 LAST BODY_TYPE PLUMBING
J 2
(-7950 3725);
DISPLAY 0.872340 (-7950 3725);
PAINT GREEN (-7950 3725);
DISPLAY INVISIBLE (-7950 3725);
FORCEPROP 1 LAST HDL_TAP TRUE
J 2
(-8275 3550);
DISPLAY 0.872340 (-8275 3550);
DISPLAY INVISIBLE (-8275 3550);
FORCEPROP 1 LAST PATH I193
J 2
(-7948 3675);
DISPLAY 0.872340 (-7948 3675);
PAINT GREEN (-7948 3675);
DISPLAY INVISIBLE (-7948 3675);
FORCEADD TAP..1
R 2
(-7950 3625);
FORCEPROP 3 LASTPIN (-7900 3625) SIG_NAME M_B_CPU0_SB_CB<6>
J 0
(-7890 3635);
DISPLAY 0.659574 (-7890 3635);
PAINT MONO (-7890 3635);
DISPLAY INVISIBLE (-7890 3635);
FORCEPROP 1 LASTPIN (-7900 3625) BN 6
J 2
(-7888 3633);
DISPLAY 0.489362 (-7888 3633);
PAINT GREEN (-7888 3633);
FORCEPROP 2 LAST CDS_LIB mstr_standard
J 0
(-7950 3625);
DISPLAY 0.723404 (-7950 3625);
PAINT MONO (-7950 3625);
DISPLAY INVISIBLE (-7950 3625);
FORCEPROP 1 LAST BODY_TYPE PLUMBING
J 2
(-7950 3675);
DISPLAY 0.872340 (-7950 3675);
PAINT GREEN (-7950 3675);
DISPLAY INVISIBLE (-7950 3675);
FORCEPROP 1 LAST HDL_TAP TRUE
J 2
(-8275 3500);
DISPLAY 0.872340 (-8275 3500);
DISPLAY INVISIBLE (-8275 3500);
FORCEPROP 1 LAST PATH I194
J 2
(-7948 3625);
DISPLAY 0.872340 (-7948 3625);
PAINT GREEN (-7948 3625);
DISPLAY INVISIBLE (-7948 3625);
FORCEADD TAP..1
R 2
(-7950 3875);
FORCEPROP 3 LASTPIN (-7900 3875) SIG_NAME M_B_CPU0_SA_CB<2>
J 0
(-7890 3885);
DISPLAY 0.659574 (-7890 3885);
PAINT MONO (-7890 3885);
DISPLAY INVISIBLE (-7890 3885);
FORCEPROP 1 LASTPIN (-7900 3875) BN 2
J 2
(-7888 3883);
DISPLAY 0.489362 (-7888 3883);
PAINT GREEN (-7888 3883);
FORCEPROP 2 LAST CDS_LIB mstr_standard
J 0
(-7950 3875);
DISPLAY 0.723404 (-7950 3875);
PAINT MONO (-7950 3875);
DISPLAY INVISIBLE (-7950 3875);
FORCEPROP 1 LAST BODY_TYPE PLUMBING
J 2
(-7950 3925);
DISPLAY 0.872340 (-7950 3925);
PAINT GREEN (-7950 3925);
DISPLAY INVISIBLE (-7950 3925);
FORCEPROP 1 LAST HDL_TAP TRUE
J 2
(-8275 3750);
DISPLAY 0.872340 (-8275 3750);
DISPLAY INVISIBLE (-8275 3750);
FORCEPROP 1 LAST PATH I195
J 2
(-7948 3875);
DISPLAY 0.872340 (-7948 3875);
PAINT GREEN (-7948 3875);
DISPLAY INVISIBLE (-7948 3875);
FORCEADD TAP..1
R 2
(-7950 3825);
FORCEPROP 3 LASTPIN (-7900 3825) SIG_NAME M_B_CPU0_SA_CB<1>
J 0
(-7890 3835);
DISPLAY 0.659574 (-7890 3835);
PAINT MONO (-7890 3835);
DISPLAY INVISIBLE (-7890 3835);
FORCEPROP 1 LASTPIN (-7900 3825) BN 1
J 2
(-7888 3833);
DISPLAY 0.489362 (-7888 3833);
PAINT GREEN (-7888 3833);
FORCEPROP 2 LAST CDS_LIB mstr_standard
J 0
(-7950 3825);
DISPLAY 0.723404 (-7950 3825);
PAINT MONO (-7950 3825);
DISPLAY INVISIBLE (-7950 3825);
FORCEPROP 1 LAST BODY_TYPE PLUMBING
J 2
(-7950 3875);
DISPLAY 0.872340 (-7950 3875);
PAINT GREEN (-7950 3875);
DISPLAY INVISIBLE (-7950 3875);
FORCEPROP 1 LAST HDL_TAP TRUE
J 2
(-8275 3700);
DISPLAY 0.872340 (-8275 3700);
DISPLAY INVISIBLE (-8275 3700);
FORCEPROP 1 LAST PATH I196
J 2
(-7948 3825);
DISPLAY 0.872340 (-7948 3825);
PAINT GREEN (-7948 3825);
DISPLAY INVISIBLE (-7948 3825);
FORCEADD TAP..1
R 2
(-7950 3775);
FORCEPROP 3 LASTPIN (-7900 3775) SIG_NAME M_B_CPU0_SA_CB<0>
J 0
(-7890 3785);
DISPLAY 0.659574 (-7890 3785);
PAINT MONO (-7890 3785);
DISPLAY INVISIBLE (-7890 3785);
FORCEPROP 1 LASTPIN (-7900 3775) BN 0
J 2
(-7888 3783);
DISPLAY 0.489362 (-7888 3783);
PAINT GREEN (-7888 3783);
FORCEPROP 2 LAST CDS_LIB mstr_standard
J 0
(-7950 3775);
DISPLAY 0.723404 (-7950 3775);
PAINT MONO (-7950 3775);
DISPLAY INVISIBLE (-7950 3775);
FORCEPROP 1 LAST BODY_TYPE PLUMBING
J 2
(-7950 3825);
DISPLAY 0.872340 (-7950 3825);
PAINT GREEN (-7950 3825);
DISPLAY INVISIBLE (-7950 3825);
FORCEPROP 1 LAST HDL_TAP TRUE
J 2
(-8275 3650);
DISPLAY 0.872340 (-8275 3650);
DISPLAY INVISIBLE (-8275 3650);
FORCEPROP 1 LAST PATH I197
J 2
(-7948 3775);
DISPLAY 0.872340 (-7948 3775);
PAINT GREEN (-7948 3775);
DISPLAY INVISIBLE (-7948 3775);
FORCEADD TAP..1
R 2
(-7950 3925);
FORCEPROP 3 LASTPIN (-7900 3925) SIG_NAME M_B_CPU0_SA_CB<3>
J 0
(-7890 3935);
DISPLAY 0.659574 (-7890 3935);
PAINT MONO (-7890 3935);
DISPLAY INVISIBLE (-7890 3935);
FORCEPROP 1 LASTPIN (-7900 3925) BN 3
J 2
(-7888 3933);
DISPLAY 0.489362 (-7888 3933);
PAINT GREEN (-7888 3933);
FORCEPROP 2 LAST CDS_LIB mstr_standard
J 0
(-7950 3925);
DISPLAY 0.723404 (-7950 3925);
PAINT MONO (-7950 3925);
DISPLAY INVISIBLE (-7950 3925);
FORCEPROP 1 LAST BODY_TYPE PLUMBING
J 2
(-7950 3975);
DISPLAY 0.872340 (-7950 3975);
PAINT GREEN (-7950 3975);
DISPLAY INVISIBLE (-7950 3975);
FORCEPROP 1 LAST HDL_TAP TRUE
J 2
(-8275 3800);
DISPLAY 0.872340 (-8275 3800);
DISPLAY INVISIBLE (-8275 3800);
FORCEPROP 1 LAST PATH I198
J 2
(-7948 3925);
DISPLAY 0.872340 (-7948 3925);
PAINT GREEN (-7948 3925);
DISPLAY INVISIBLE (-7948 3925);
FORCEADD TAP..1
R 2
(-7950 3975);
FORCEPROP 3 LASTPIN (-7900 3975) SIG_NAME M_B_CPU0_SA_CB<4>
J 0
(-7890 3985);
DISPLAY 0.659574 (-7890 3985);
PAINT MONO (-7890 3985);
DISPLAY INVISIBLE (-7890 3985);
FORCEPROP 1 LASTPIN (-7900 3975) BN 4
J 2
(-7888 3983);
DISPLAY 0.489362 (-7888 3983);
PAINT GREEN (-7888 3983);
FORCEPROP 2 LAST CDS_LIB mstr_standard
J 0
(-7950 3975);
DISPLAY 0.723404 (-7950 3975);
PAINT MONO (-7950 3975);
DISPLAY INVISIBLE (-7950 3975);
FORCEPROP 1 LAST BODY_TYPE PLUMBING
J 2
(-7950 4025);
DISPLAY 0.872340 (-7950 4025);
PAINT GREEN (-7950 4025);
DISPLAY INVISIBLE (-7950 4025);
FORCEPROP 1 LAST HDL_TAP TRUE
J 2
(-8275 3850);
DISPLAY 0.872340 (-8275 3850);
DISPLAY INVISIBLE (-8275 3850);
FORCEPROP 1 LAST PATH I199
J 2
(-7948 3975);
DISPLAY 0.872340 (-7948 3975);
PAINT GREEN (-7948 3975);
DISPLAY INVISIBLE (-7948 3975);
FORCEADD TAP..1
R 2
(-7950 4025);
FORCEPROP 3 LASTPIN (-7900 4025) SIG_NAME M_B_CPU0_SA_CB<5>
J 0
(-7890 4035);
DISPLAY 0.659574 (-7890 4035);
PAINT MONO (-7890 4035);
DISPLAY INVISIBLE (-7890 4035);
FORCEPROP 1 LASTPIN (-7900 4025) BN 5
J 2
(-7888 4033);
DISPLAY 0.489362 (-7888 4033);
PAINT GREEN (-7888 4033);
FORCEPROP 2 LAST CDS_LIB mstr_standard
J 0
(-7950 4025);
DISPLAY 0.723404 (-7950 4025);
PAINT MONO (-7950 4025);
DISPLAY INVISIBLE (-7950 4025);
FORCEPROP 1 LAST BODY_TYPE PLUMBING
J 2
(-7950 4075);
DISPLAY 0.872340 (-7950 4075);
PAINT GREEN (-7950 4075);
DISPLAY INVISIBLE (-7950 4075);
FORCEPROP 1 LAST HDL_TAP TRUE
J 2
(-8275 3900);
DISPLAY 0.872340 (-8275 3900);
DISPLAY INVISIBLE (-8275 3900);
FORCEPROP 1 LAST PATH I200
J 2
(-7948 4025);
DISPLAY 0.872340 (-7948 4025);
PAINT GREEN (-7948 4025);
DISPLAY INVISIBLE (-7948 4025);
FORCEADD TAP..1
R 2
(-7950 4075);
FORCEPROP 3 LASTPIN (-7900 4075) SIG_NAME M_B_CPU0_SA_CB<6>
J 0
(-7890 4085);
DISPLAY 0.659574 (-7890 4085);
PAINT MONO (-7890 4085);
DISPLAY INVISIBLE (-7890 4085);
FORCEPROP 1 LASTPIN (-7900 4075) BN 6
J 2
(-7888 4083);
DISPLAY 0.489362 (-7888 4083);
PAINT GREEN (-7888 4083);
FORCEPROP 2 LAST CDS_LIB mstr_standard
J 0
(-7950 4075);
DISPLAY 0.723404 (-7950 4075);
PAINT MONO (-7950 4075);
DISPLAY INVISIBLE (-7950 4075);
FORCEPROP 1 LAST BODY_TYPE PLUMBING
J 2
(-7950 4125);
DISPLAY 0.872340 (-7950 4125);
PAINT GREEN (-7950 4125);
DISPLAY INVISIBLE (-7950 4125);
FORCEPROP 1 LAST HDL_TAP TRUE
J 2
(-8275 3950);
DISPLAY 0.872340 (-8275 3950);
DISPLAY INVISIBLE (-8275 3950);
FORCEPROP 1 LAST PATH I201
J 2
(-7948 4075);
DISPLAY 0.872340 (-7948 4075);
PAINT GREEN (-7948 4075);
DISPLAY INVISIBLE (-7948 4075);
FORCEADD TAP..1
R 2
(-7950 4125);
FORCEPROP 3 LASTPIN (-7900 4125) SIG_NAME M_B_CPU0_SA_CB<7>
J 0
(-7890 4135);
DISPLAY 0.659574 (-7890 4135);
PAINT MONO (-7890 4135);
DISPLAY INVISIBLE (-7890 4135);
FORCEPROP 1 LASTPIN (-7900 4125) BN 7
J 2
(-7888 4133);
DISPLAY 0.489362 (-7888 4133);
PAINT GREEN (-7888 4133);
FORCEPROP 2 LAST CDS_LIB mstr_standard
J 0
(-7950 4125);
DISPLAY 0.723404 (-7950 4125);
PAINT MONO (-7950 4125);
DISPLAY INVISIBLE (-7950 4125);
FORCEPROP 1 LAST BODY_TYPE PLUMBING
J 2
(-7950 4175);
DISPLAY 0.872340 (-7950 4175);
PAINT GREEN (-7950 4175);
DISPLAY INVISIBLE (-7950 4175);
FORCEPROP 1 LAST HDL_TAP TRUE
J 2
(-8275 4000);
DISPLAY 0.872340 (-8275 4000);
DISPLAY INVISIBLE (-8275 4000);
FORCEPROP 1 LAST PATH I202
J 2
(-7948 4125);
DISPLAY 0.872340 (-7948 4125);
PAINT GREEN (-7948 4125);
DISPLAY INVISIBLE (-7948 4125);
FORCEADD TAP..1
R 2
(-7950 4975);
FORCEPROP 3 LASTPIN (-7900 4975) SIG_NAME M_B_CPU0_SB_CA<3>
J 0
(-7890 4985);
DISPLAY 0.659574 (-7890 4985);
PAINT MONO (-7890 4985);
DISPLAY INVISIBLE (-7890 4985);
FORCEPROP 1 LASTPIN (-7900 4975) BN 3
J 2
(-7888 4983);
DISPLAY 0.489362 (-7888 4983);
PAINT GREEN (-7888 4983);
FORCEPROP 2 LAST CDS_LIB mstr_standard
J 0
(-7950 4975);
DISPLAY 0.723404 (-7950 4975);
PAINT MONO (-7950 4975);
DISPLAY INVISIBLE (-7950 4975);
FORCEPROP 1 LAST BODY_TYPE PLUMBING
J 2
(-7950 5025);
DISPLAY 0.872340 (-7950 5025);
PAINT GREEN (-7950 5025);
DISPLAY INVISIBLE (-7950 5025);
FORCEPROP 1 LAST HDL_TAP TRUE
J 2
(-8275 4850);
DISPLAY 0.872340 (-8275 4850);
DISPLAY INVISIBLE (-8275 4850);
FORCEPROP 1 LAST PATH I203
J 2
(-7948 4975);
DISPLAY 0.872340 (-7948 4975);
PAINT GREEN (-7948 4975);
DISPLAY INVISIBLE (-7948 4975);
FORCEADD TAP..1
R 2
(-7950 4875);
FORCEPROP 3 LASTPIN (-7900 4875) SIG_NAME M_B_CPU0_SB_CA<1>
J 0
(-7890 4885);
DISPLAY 0.659574 (-7890 4885);
PAINT MONO (-7890 4885);
DISPLAY INVISIBLE (-7890 4885);
FORCEPROP 1 LASTPIN (-7900 4875) BN 1
J 2
(-7888 4883);
DISPLAY 0.489362 (-7888 4883);
PAINT GREEN (-7888 4883);
FORCEPROP 2 LAST CDS_LIB mstr_standard
J 0
(-7950 4875);
DISPLAY 0.723404 (-7950 4875);
PAINT MONO (-7950 4875);
DISPLAY INVISIBLE (-7950 4875);
FORCEPROP 1 LAST BODY_TYPE PLUMBING
J 2
(-7950 4925);
DISPLAY 0.872340 (-7950 4925);
PAINT GREEN (-7950 4925);
DISPLAY INVISIBLE (-7950 4925);
FORCEPROP 1 LAST HDL_TAP TRUE
J 2
(-8275 4750);
DISPLAY 0.872340 (-8275 4750);
DISPLAY INVISIBLE (-8275 4750);
FORCEPROP 1 LAST PATH I204
J 2
(-7948 4875);
DISPLAY 0.872340 (-7948 4875);
PAINT GREEN (-7948 4875);
DISPLAY INVISIBLE (-7948 4875);
FORCEADD TAP..1
R 2
(-7950 4825);
FORCEPROP 3 LASTPIN (-7900 4825) SIG_NAME M_B_CPU0_SB_CA<0>
J 0
(-7890 4835);
DISPLAY 0.659574 (-7890 4835);
PAINT MONO (-7890 4835);
DISPLAY INVISIBLE (-7890 4835);
FORCEPROP 1 LASTPIN (-7900 4825) BN 0
J 2
(-7888 4833);
DISPLAY 0.489362 (-7888 4833);
PAINT GREEN (-7888 4833);
FORCEPROP 2 LAST CDS_LIB mstr_standard
J 0
(-7950 4825);
DISPLAY 0.723404 (-7950 4825);
PAINT MONO (-7950 4825);
DISPLAY INVISIBLE (-7950 4825);
FORCEPROP 1 LAST BODY_TYPE PLUMBING
J 2
(-7950 4875);
DISPLAY 0.872340 (-7950 4875);
PAINT GREEN (-7950 4875);
DISPLAY INVISIBLE (-7950 4875);
FORCEPROP 1 LAST HDL_TAP TRUE
J 2
(-8275 4700);
DISPLAY 0.872340 (-8275 4700);
DISPLAY INVISIBLE (-8275 4700);
FORCEPROP 1 LAST PATH I205
J 2
(-7948 4825);
DISPLAY 0.872340 (-7948 4825);
PAINT GREEN (-7948 4825);
DISPLAY INVISIBLE (-7948 4825);
FORCEADD TAP..1
R 2
(-7950 4925);
FORCEPROP 3 LASTPIN (-7900 4925) SIG_NAME M_B_CPU0_SB_CA<2>
J 0
(-7890 4935);
DISPLAY 0.659574 (-7890 4935);
PAINT MONO (-7890 4935);
DISPLAY INVISIBLE (-7890 4935);
FORCEPROP 1 LASTPIN (-7900 4925) BN 2
J 2
(-7888 4933);
DISPLAY 0.489362 (-7888 4933);
PAINT GREEN (-7888 4933);
FORCEPROP 2 LAST CDS_LIB mstr_standard
J 0
(-7950 4925);
DISPLAY 0.723404 (-7950 4925);
PAINT MONO (-7950 4925);
DISPLAY INVISIBLE (-7950 4925);
FORCEPROP 1 LAST BODY_TYPE PLUMBING
J 2
(-7950 4975);
DISPLAY 0.872340 (-7950 4975);
PAINT GREEN (-7950 4975);
DISPLAY INVISIBLE (-7950 4975);
FORCEPROP 1 LAST HDL_TAP TRUE
J 2
(-8275 4800);
DISPLAY 0.872340 (-8275 4800);
DISPLAY INVISIBLE (-8275 4800);
FORCEPROP 1 LAST PATH I206
J 2
(-7948 4925);
DISPLAY 0.872340 (-7948 4925);
PAINT GREEN (-7948 4925);
DISPLAY INVISIBLE (-7948 4925);
FORCEADD TAP..1
(-6250 2375);
FORCEPROP 3 LASTPIN (-6300 2375) SIG_NAME M_B_CPU0_SB_DQ<1>
J 0
(-6290 2385);
DISPLAY 0.659574 (-6290 2385);
PAINT MONO (-6290 2385);
DISPLAY INVISIBLE (-6290 2385);
FORCEPROP 1 LASTPIN (-6300 2375) BN 1
J 0
(-6312 2383);
DISPLAY 0.489362 (-6312 2383);
PAINT GREEN (-6312 2383);
FORCEPROP 2 LAST CDS_LIB mstr_standard
J 0
(-6250 2375);
DISPLAY 0.723404 (-6250 2375);
PAINT MONO (-6250 2375);
DISPLAY INVISIBLE (-6250 2375);
FORCEPROP 1 LAST BODY_TYPE PLUMBING
J 0
(-6250 2425);
DISPLAY 0.872340 (-6250 2425);
PAINT GREEN (-6250 2425);
DISPLAY INVISIBLE (-6250 2425);
FORCEPROP 1 LAST HDL_TAP TRUE
J 0
(-5925 2250);
DISPLAY 0.872340 (-5925 2250);
DISPLAY INVISIBLE (-5925 2250);
FORCEPROP 1 LAST PATH I207
J 0
(-6252 2375);
DISPLAY 0.872340 (-6252 2375);
PAINT GREEN (-6252 2375);
DISPLAY INVISIBLE (-6252 2375);
FORCEADD TAP..1
(-6250 2325);
FORCEPROP 3 LASTPIN (-6300 2325) SIG_NAME M_B_CPU0_SB_DQ<0>
J 0
(-6290 2335);
DISPLAY 0.659574 (-6290 2335);
PAINT MONO (-6290 2335);
DISPLAY INVISIBLE (-6290 2335);
FORCEPROP 1 LASTPIN (-6300 2325) BN 0
J 0
(-6312 2333);
DISPLAY 0.489362 (-6312 2333);
PAINT GREEN (-6312 2333);
FORCEPROP 2 LAST CDS_LIB mstr_standard
J 0
(-6250 2325);
DISPLAY 0.723404 (-6250 2325);
PAINT MONO (-6250 2325);
DISPLAY INVISIBLE (-6250 2325);
FORCEPROP 1 LAST BODY_TYPE PLUMBING
J 0
(-6250 2375);
DISPLAY 0.872340 (-6250 2375);
PAINT GREEN (-6250 2375);
DISPLAY INVISIBLE (-6250 2375);
FORCEPROP 1 LAST HDL_TAP TRUE
J 0
(-5925 2200);
DISPLAY 0.872340 (-5925 2200);
DISPLAY INVISIBLE (-5925 2200);
FORCEPROP 1 LAST PATH I208
J 0
(-6252 2325);
DISPLAY 0.872340 (-6252 2325);
PAINT GREEN (-6252 2325);
DISPLAY INVISIBLE (-6252 2325);
FORCEADD TAP..1
(-6250 2425);
FORCEPROP 3 LASTPIN (-6300 2425) SIG_NAME M_B_CPU0_SB_DQ<2>
J 0
(-6290 2435);
DISPLAY 0.659574 (-6290 2435);
PAINT MONO (-6290 2435);
DISPLAY INVISIBLE (-6290 2435);
FORCEPROP 1 LASTPIN (-6300 2425) BN 2
J 0
(-6312 2433);
DISPLAY 0.489362 (-6312 2433);
PAINT GREEN (-6312 2433);
FORCEPROP 2 LAST CDS_LIB mstr_standard
J 0
(-6250 2425);
DISPLAY 0.723404 (-6250 2425);
PAINT MONO (-6250 2425);
DISPLAY INVISIBLE (-6250 2425);
FORCEPROP 1 LAST BODY_TYPE PLUMBING
J 0
(-6250 2475);
DISPLAY 0.872340 (-6250 2475);
PAINT GREEN (-6250 2475);
DISPLAY INVISIBLE (-6250 2475);
FORCEPROP 1 LAST HDL_TAP TRUE
J 0
(-5925 2300);
DISPLAY 0.872340 (-5925 2300);
DISPLAY INVISIBLE (-5925 2300);
FORCEPROP 1 LAST PATH I209
J 0
(-6252 2425);
DISPLAY 0.872340 (-6252 2425);
PAINT GREEN (-6252 2425);
DISPLAY INVISIBLE (-6252 2425);
FORCEADD TAP..1
(-6250 2475);
FORCEPROP 3 LASTPIN (-6300 2475) SIG_NAME M_B_CPU0_SB_DQ<3>
J 0
(-6290 2485);
DISPLAY 0.659574 (-6290 2485);
PAINT MONO (-6290 2485);
DISPLAY INVISIBLE (-6290 2485);
FORCEPROP 1 LASTPIN (-6300 2475) BN 3
J 0
(-6312 2483);
DISPLAY 0.489362 (-6312 2483);
PAINT GREEN (-6312 2483);
FORCEPROP 2 LAST CDS_LIB mstr_standard
J 0
(-6250 2475);
DISPLAY 0.723404 (-6250 2475);
PAINT MONO (-6250 2475);
DISPLAY INVISIBLE (-6250 2475);
FORCEPROP 1 LAST BODY_TYPE PLUMBING
J 0
(-6250 2525);
DISPLAY 0.872340 (-6250 2525);
PAINT GREEN (-6250 2525);
DISPLAY INVISIBLE (-6250 2525);
FORCEPROP 1 LAST HDL_TAP TRUE
J 0
(-5925 2350);
DISPLAY 0.872340 (-5925 2350);
DISPLAY INVISIBLE (-5925 2350);
FORCEPROP 1 LAST PATH I210
J 0
(-6252 2475);
DISPLAY 0.872340 (-6252 2475);
PAINT GREEN (-6252 2475);
DISPLAY INVISIBLE (-6252 2475);
FORCEADD TAP..1
(-6250 2525);
FORCEPROP 3 LASTPIN (-6300 2525) SIG_NAME M_B_CPU0_SB_DQ<4>
J 0
(-6290 2535);
DISPLAY 0.659574 (-6290 2535);
PAINT MONO (-6290 2535);
DISPLAY INVISIBLE (-6290 2535);
FORCEPROP 1 LASTPIN (-6300 2525) BN 4
J 0
(-6312 2533);
DISPLAY 0.489362 (-6312 2533);
PAINT GREEN (-6312 2533);
FORCEPROP 2 LAST CDS_LIB mstr_standard
J 0
(-6250 2525);
DISPLAY 0.723404 (-6250 2525);
PAINT MONO (-6250 2525);
DISPLAY INVISIBLE (-6250 2525);
FORCEPROP 1 LAST BODY_TYPE PLUMBING
J 0
(-6250 2575);
DISPLAY 0.872340 (-6250 2575);
PAINT GREEN (-6250 2575);
DISPLAY INVISIBLE (-6250 2575);
FORCEPROP 1 LAST HDL_TAP TRUE
J 0
(-5925 2400);
DISPLAY 0.872340 (-5925 2400);
DISPLAY INVISIBLE (-5925 2400);
FORCEPROP 1 LAST PATH I211
J 0
(-6252 2525);
DISPLAY 0.872340 (-6252 2525);
PAINT GREEN (-6252 2525);
DISPLAY INVISIBLE (-6252 2525);
FORCEADD TAP..1
(-6250 2575);
FORCEPROP 3 LASTPIN (-6300 2575) SIG_NAME M_B_CPU0_SB_DQ<5>
J 0
(-6290 2585);
DISPLAY 0.659574 (-6290 2585);
PAINT MONO (-6290 2585);
DISPLAY INVISIBLE (-6290 2585);
FORCEPROP 1 LASTPIN (-6300 2575) BN 5
J 0
(-6312 2583);
DISPLAY 0.489362 (-6312 2583);
PAINT GREEN (-6312 2583);
FORCEPROP 2 LAST CDS_LIB mstr_standard
J 0
(-6250 2575);
DISPLAY 0.723404 (-6250 2575);
PAINT MONO (-6250 2575);
DISPLAY INVISIBLE (-6250 2575);
FORCEPROP 1 LAST BODY_TYPE PLUMBING
J 0
(-6250 2625);
DISPLAY 0.872340 (-6250 2625);
PAINT GREEN (-6250 2625);
DISPLAY INVISIBLE (-6250 2625);
FORCEPROP 1 LAST HDL_TAP TRUE
J 0
(-5925 2450);
DISPLAY 0.872340 (-5925 2450);
DISPLAY INVISIBLE (-5925 2450);
FORCEPROP 1 LAST PATH I212
J 0
(-6252 2575);
DISPLAY 0.872340 (-6252 2575);
PAINT GREEN (-6252 2575);
DISPLAY INVISIBLE (-6252 2575);
FORCEADD TAP..1
(-6250 2675);
FORCEPROP 3 LASTPIN (-6300 2675) SIG_NAME M_B_CPU0_SB_DQ<7>
J 0
(-6290 2685);
DISPLAY 0.659574 (-6290 2685);
PAINT MONO (-6290 2685);
DISPLAY INVISIBLE (-6290 2685);
FORCEPROP 1 LASTPIN (-6300 2675) BN 7
J 0
(-6312 2683);
DISPLAY 0.489362 (-6312 2683);
PAINT GREEN (-6312 2683);
FORCEPROP 2 LAST CDS_LIB mstr_standard
J 0
(-6250 2675);
DISPLAY 0.723404 (-6250 2675);
PAINT MONO (-6250 2675);
DISPLAY INVISIBLE (-6250 2675);
FORCEPROP 1 LAST BODY_TYPE PLUMBING
J 0
(-6250 2725);
DISPLAY 0.872340 (-6250 2725);
PAINT GREEN (-6250 2725);
DISPLAY INVISIBLE (-6250 2725);
FORCEPROP 1 LAST HDL_TAP TRUE
J 0
(-5925 2550);
DISPLAY 0.872340 (-5925 2550);
DISPLAY INVISIBLE (-5925 2550);
FORCEPROP 1 LAST PATH I213
J 0
(-6252 2675);
DISPLAY 0.872340 (-6252 2675);
PAINT GREEN (-6252 2675);
DISPLAY INVISIBLE (-6252 2675);
FORCEADD TAP..1
(-6250 2625);
FORCEPROP 3 LASTPIN (-6300 2625) SIG_NAME M_B_CPU0_SB_DQ<6>
J 0
(-6290 2635);
DISPLAY 0.659574 (-6290 2635);
PAINT MONO (-6290 2635);
DISPLAY INVISIBLE (-6290 2635);
FORCEPROP 1 LASTPIN (-6300 2625) BN 6
J 0
(-6312 2633);
DISPLAY 0.489362 (-6312 2633);
PAINT GREEN (-6312 2633);
FORCEPROP 2 LAST CDS_LIB mstr_standard
J 0
(-6250 2625);
DISPLAY 0.723404 (-6250 2625);
PAINT MONO (-6250 2625);
DISPLAY INVISIBLE (-6250 2625);
FORCEPROP 1 LAST BODY_TYPE PLUMBING
J 0
(-6250 2675);
DISPLAY 0.872340 (-6250 2675);
PAINT GREEN (-6250 2675);
DISPLAY INVISIBLE (-6250 2675);
FORCEPROP 1 LAST HDL_TAP TRUE
J 0
(-5925 2500);
DISPLAY 0.872340 (-5925 2500);
DISPLAY INVISIBLE (-5925 2500);
FORCEPROP 1 LAST PATH I214
J 0
(-6252 2625);
DISPLAY 0.872340 (-6252 2625);
PAINT GREEN (-6252 2625);
DISPLAY INVISIBLE (-6252 2625);
FORCEADD TAP..1
(-6250 2725);
FORCEPROP 3 LASTPIN (-6300 2725) SIG_NAME M_B_CPU0_SB_DQ<8>
J 0
(-6290 2735);
DISPLAY 0.659574 (-6290 2735);
PAINT MONO (-6290 2735);
DISPLAY INVISIBLE (-6290 2735);
FORCEPROP 1 LASTPIN (-6300 2725) BN 8
J 0
(-6312 2733);
DISPLAY 0.489362 (-6312 2733);
PAINT GREEN (-6312 2733);
FORCEPROP 2 LAST CDS_LIB mstr_standard
J 0
(-6250 2725);
DISPLAY 0.723404 (-6250 2725);
PAINT MONO (-6250 2725);
DISPLAY INVISIBLE (-6250 2725);
FORCEPROP 1 LAST BODY_TYPE PLUMBING
J 0
(-6250 2775);
DISPLAY 0.872340 (-6250 2775);
PAINT GREEN (-6250 2775);
DISPLAY INVISIBLE (-6250 2775);
FORCEPROP 1 LAST HDL_TAP TRUE
J 0
(-5925 2600);
DISPLAY 0.872340 (-5925 2600);
DISPLAY INVISIBLE (-5925 2600);
FORCEPROP 1 LAST PATH I215
J 0
(-6252 2725);
DISPLAY 0.872340 (-6252 2725);
PAINT GREEN (-6252 2725);
DISPLAY INVISIBLE (-6252 2725);
FORCEADD TAP..1
(-6250 2775);
FORCEPROP 3 LASTPIN (-6300 2775) SIG_NAME M_B_CPU0_SB_DQ<9>
J 0
(-6290 2785);
DISPLAY 0.659574 (-6290 2785);
PAINT MONO (-6290 2785);
DISPLAY INVISIBLE (-6290 2785);
FORCEPROP 1 LASTPIN (-6300 2775) BN 9
J 0
(-6312 2783);
DISPLAY 0.489362 (-6312 2783);
PAINT GREEN (-6312 2783);
FORCEPROP 2 LAST CDS_LIB mstr_standard
J 0
(-6250 2775);
DISPLAY 0.723404 (-6250 2775);
PAINT MONO (-6250 2775);
DISPLAY INVISIBLE (-6250 2775);
FORCEPROP 1 LAST BODY_TYPE PLUMBING
J 0
(-6250 2825);
DISPLAY 0.872340 (-6250 2825);
PAINT GREEN (-6250 2825);
DISPLAY INVISIBLE (-6250 2825);
FORCEPROP 1 LAST HDL_TAP TRUE
J 0
(-5925 2650);
DISPLAY 0.872340 (-5925 2650);
DISPLAY INVISIBLE (-5925 2650);
FORCEPROP 1 LAST PATH I216
J 0
(-6252 2775);
DISPLAY 0.872340 (-6252 2775);
PAINT GREEN (-6252 2775);
DISPLAY INVISIBLE (-6252 2775);
FORCEADD TAP..1
(-6250 2825);
FORCEPROP 3 LASTPIN (-6300 2825) SIG_NAME M_B_CPU0_SB_DQ<10>
J 0
(-6290 2835);
DISPLAY 0.659574 (-6290 2835);
PAINT MONO (-6290 2835);
DISPLAY INVISIBLE (-6290 2835);
FORCEPROP 1 LASTPIN (-6300 2825) BN 10
J 0
(-6312 2833);
DISPLAY 0.489362 (-6312 2833);
PAINT GREEN (-6312 2833);
FORCEPROP 2 LAST CDS_LIB mstr_standard
J 0
(-6250 2825);
DISPLAY 0.723404 (-6250 2825);
PAINT MONO (-6250 2825);
DISPLAY INVISIBLE (-6250 2825);
FORCEPROP 1 LAST BODY_TYPE PLUMBING
J 0
(-6250 2875);
DISPLAY 0.872340 (-6250 2875);
PAINT GREEN (-6250 2875);
DISPLAY INVISIBLE (-6250 2875);
FORCEPROP 1 LAST HDL_TAP TRUE
J 0
(-5925 2700);
DISPLAY 0.872340 (-5925 2700);
DISPLAY INVISIBLE (-5925 2700);
FORCEPROP 1 LAST PATH I217
J 0
(-6252 2825);
DISPLAY 0.872340 (-6252 2825);
PAINT GREEN (-6252 2825);
DISPLAY INVISIBLE (-6252 2825);
FORCEADD TAP..1
(-6250 2875);
FORCEPROP 3 LASTPIN (-6300 2875) SIG_NAME M_B_CPU0_SB_DQ<11>
J 0
(-6290 2885);
DISPLAY 0.659574 (-6290 2885);
PAINT MONO (-6290 2885);
DISPLAY INVISIBLE (-6290 2885);
FORCEPROP 1 LASTPIN (-6300 2875) BN 11
J 0
(-6312 2883);
DISPLAY 0.489362 (-6312 2883);
PAINT GREEN (-6312 2883);
FORCEPROP 2 LAST CDS_LIB mstr_standard
J 0
(-6250 2875);
DISPLAY 0.723404 (-6250 2875);
PAINT MONO (-6250 2875);
DISPLAY INVISIBLE (-6250 2875);
FORCEPROP 1 LAST BODY_TYPE PLUMBING
J 0
(-6250 2925);
DISPLAY 0.872340 (-6250 2925);
PAINT GREEN (-6250 2925);
DISPLAY INVISIBLE (-6250 2925);
FORCEPROP 1 LAST HDL_TAP TRUE
J 0
(-5925 2750);
DISPLAY 0.872340 (-5925 2750);
DISPLAY INVISIBLE (-5925 2750);
FORCEPROP 1 LAST PATH I218
J 0
(-6252 2875);
DISPLAY 0.872340 (-6252 2875);
PAINT GREEN (-6252 2875);
DISPLAY INVISIBLE (-6252 2875);
FORCEADD TAP..1
(-6250 2925);
FORCEPROP 3 LASTPIN (-6300 2925) SIG_NAME M_B_CPU0_SB_DQ<12>
J 0
(-6290 2935);
DISPLAY 0.659574 (-6290 2935);
PAINT MONO (-6290 2935);
DISPLAY INVISIBLE (-6290 2935);
FORCEPROP 1 LASTPIN (-6300 2925) BN 12
J 0
(-6312 2933);
DISPLAY 0.489362 (-6312 2933);
PAINT GREEN (-6312 2933);
FORCEPROP 2 LAST CDS_LIB mstr_standard
J 0
(-6250 2925);
DISPLAY 0.723404 (-6250 2925);
PAINT MONO (-6250 2925);
DISPLAY INVISIBLE (-6250 2925);
FORCEPROP 1 LAST BODY_TYPE PLUMBING
J 0
(-6250 2975);
DISPLAY 0.872340 (-6250 2975);
PAINT GREEN (-6250 2975);
DISPLAY INVISIBLE (-6250 2975);
FORCEPROP 1 LAST HDL_TAP TRUE
J 0
(-5925 2800);
DISPLAY 0.872340 (-5925 2800);
DISPLAY INVISIBLE (-5925 2800);
FORCEPROP 1 LAST PATH I219
J 0
(-6252 2925);
DISPLAY 0.872340 (-6252 2925);
PAINT GREEN (-6252 2925);
DISPLAY INVISIBLE (-6252 2925);
FORCEADD TAP..1
(-6250 2975);
FORCEPROP 3 LASTPIN (-6300 2975) SIG_NAME M_B_CPU0_SB_DQ<13>
J 0
(-6290 2985);
DISPLAY 0.659574 (-6290 2985);
PAINT MONO (-6290 2985);
DISPLAY INVISIBLE (-6290 2985);
FORCEPROP 1 LASTPIN (-6300 2975) BN 13
J 0
(-6312 2983);
DISPLAY 0.489362 (-6312 2983);
PAINT GREEN (-6312 2983);
FORCEPROP 2 LAST CDS_LIB mstr_standard
J 0
(-6250 2975);
DISPLAY 0.723404 (-6250 2975);
PAINT MONO (-6250 2975);
DISPLAY INVISIBLE (-6250 2975);
FORCEPROP 1 LAST BODY_TYPE PLUMBING
J 0
(-6250 3025);
DISPLAY 0.872340 (-6250 3025);
PAINT GREEN (-6250 3025);
DISPLAY INVISIBLE (-6250 3025);
FORCEPROP 1 LAST HDL_TAP TRUE
J 0
(-5925 2850);
DISPLAY 0.872340 (-5925 2850);
DISPLAY INVISIBLE (-5925 2850);
FORCEPROP 1 LAST PATH I220
J 0
(-6252 2975);
DISPLAY 0.872340 (-6252 2975);
PAINT GREEN (-6252 2975);
DISPLAY INVISIBLE (-6252 2975);
FORCEADD TAP..1
(-6250 3075);
FORCEPROP 3 LASTPIN (-6300 3075) SIG_NAME M_B_CPU0_SB_DQ<15>
J 0
(-6290 3085);
DISPLAY 0.659574 (-6290 3085);
PAINT MONO (-6290 3085);
DISPLAY INVISIBLE (-6290 3085);
FORCEPROP 1 LASTPIN (-6300 3075) BN 15
J 0
(-6312 3083);
DISPLAY 0.489362 (-6312 3083);
PAINT GREEN (-6312 3083);
FORCEPROP 2 LAST CDS_LIB mstr_standard
J 0
(-6250 3075);
DISPLAY 0.723404 (-6250 3075);
PAINT MONO (-6250 3075);
DISPLAY INVISIBLE (-6250 3075);
FORCEPROP 1 LAST BODY_TYPE PLUMBING
J 0
(-6250 3125);
DISPLAY 0.872340 (-6250 3125);
PAINT GREEN (-6250 3125);
DISPLAY INVISIBLE (-6250 3125);
FORCEPROP 1 LAST HDL_TAP TRUE
J 0
(-5925 2950);
DISPLAY 0.872340 (-5925 2950);
DISPLAY INVISIBLE (-5925 2950);
FORCEPROP 1 LAST PATH I221
J 0
(-6252 3075);
DISPLAY 0.872340 (-6252 3075);
PAINT GREEN (-6252 3075);
DISPLAY INVISIBLE (-6252 3075);
FORCEADD TAP..1
(-6250 3025);
FORCEPROP 3 LASTPIN (-6300 3025) SIG_NAME M_B_CPU0_SB_DQ<14>
J 0
(-6290 3035);
DISPLAY 0.659574 (-6290 3035);
PAINT MONO (-6290 3035);
DISPLAY INVISIBLE (-6290 3035);
FORCEPROP 1 LASTPIN (-6300 3025) BN 14
J 0
(-6312 3033);
DISPLAY 0.489362 (-6312 3033);
PAINT GREEN (-6312 3033);
FORCEPROP 2 LAST CDS_LIB mstr_standard
J 0
(-6250 3025);
DISPLAY 0.723404 (-6250 3025);
PAINT MONO (-6250 3025);
DISPLAY INVISIBLE (-6250 3025);
FORCEPROP 1 LAST BODY_TYPE PLUMBING
J 0
(-6250 3075);
DISPLAY 0.872340 (-6250 3075);
PAINT GREEN (-6250 3075);
DISPLAY INVISIBLE (-6250 3075);
FORCEPROP 1 LAST HDL_TAP TRUE
J 0
(-5925 2900);
DISPLAY 0.872340 (-5925 2900);
DISPLAY INVISIBLE (-5925 2900);
FORCEPROP 1 LAST PATH I222
J 0
(-6252 3025);
DISPLAY 0.872340 (-6252 3025);
PAINT GREEN (-6252 3025);
DISPLAY INVISIBLE (-6252 3025);
FORCEADD TAP..1
(-6250 3225);
FORCEPROP 3 LASTPIN (-6300 3225) SIG_NAME M_B_CPU0_SB_DQ<18>
J 0
(-6290 3235);
DISPLAY 0.659574 (-6290 3235);
PAINT MONO (-6290 3235);
DISPLAY INVISIBLE (-6290 3235);
FORCEPROP 1 LASTPIN (-6300 3225) BN 18
J 0
(-6312 3233);
DISPLAY 0.489362 (-6312 3233);
PAINT GREEN (-6312 3233);
FORCEPROP 2 LAST CDS_LIB mstr_standard
J 0
(-6250 3225);
DISPLAY 0.723404 (-6250 3225);
PAINT MONO (-6250 3225);
DISPLAY INVISIBLE (-6250 3225);
FORCEPROP 1 LAST BODY_TYPE PLUMBING
J 0
(-6250 3275);
DISPLAY 0.872340 (-6250 3275);
PAINT GREEN (-6250 3275);
DISPLAY INVISIBLE (-6250 3275);
FORCEPROP 1 LAST HDL_TAP TRUE
J 0
(-5925 3100);
DISPLAY 0.872340 (-5925 3100);
DISPLAY INVISIBLE (-5925 3100);
FORCEPROP 1 LAST PATH I223
J 0
(-6252 3225);
DISPLAY 0.872340 (-6252 3225);
PAINT GREEN (-6252 3225);
DISPLAY INVISIBLE (-6252 3225);
FORCEADD TAP..1
(-6250 3175);
FORCEPROP 3 LASTPIN (-6300 3175) SIG_NAME M_B_CPU0_SB_DQ<17>
J 0
(-6290 3185);
DISPLAY 0.659574 (-6290 3185);
PAINT MONO (-6290 3185);
DISPLAY INVISIBLE (-6290 3185);
FORCEPROP 1 LASTPIN (-6300 3175) BN 17
J 0
(-6312 3183);
DISPLAY 0.489362 (-6312 3183);
PAINT GREEN (-6312 3183);
FORCEPROP 2 LAST CDS_LIB mstr_standard
J 0
(-6250 3175);
DISPLAY 0.723404 (-6250 3175);
PAINT MONO (-6250 3175);
DISPLAY INVISIBLE (-6250 3175);
FORCEPROP 1 LAST BODY_TYPE PLUMBING
J 0
(-6250 3225);
DISPLAY 0.872340 (-6250 3225);
PAINT GREEN (-6250 3225);
DISPLAY INVISIBLE (-6250 3225);
FORCEPROP 1 LAST HDL_TAP TRUE
J 0
(-5925 3050);
DISPLAY 0.872340 (-5925 3050);
DISPLAY INVISIBLE (-5925 3050);
FORCEPROP 1 LAST PATH I224
J 0
(-6252 3175);
DISPLAY 0.872340 (-6252 3175);
PAINT GREEN (-6252 3175);
DISPLAY INVISIBLE (-6252 3175);
FORCEADD TAP..1
(-6250 3125);
FORCEPROP 3 LASTPIN (-6300 3125) SIG_NAME M_B_CPU0_SB_DQ<16>
J 0
(-6290 3135);
DISPLAY 0.659574 (-6290 3135);
PAINT MONO (-6290 3135);
DISPLAY INVISIBLE (-6290 3135);
FORCEPROP 1 LASTPIN (-6300 3125) BN 16
J 0
(-6312 3133);
DISPLAY 0.489362 (-6312 3133);
PAINT GREEN (-6312 3133);
FORCEPROP 2 LAST CDS_LIB mstr_standard
J 0
(-6250 3125);
DISPLAY 0.723404 (-6250 3125);
PAINT MONO (-6250 3125);
DISPLAY INVISIBLE (-6250 3125);
FORCEPROP 1 LAST BODY_TYPE PLUMBING
J 0
(-6250 3175);
DISPLAY 0.872340 (-6250 3175);
PAINT GREEN (-6250 3175);
DISPLAY INVISIBLE (-6250 3175);
FORCEPROP 1 LAST HDL_TAP TRUE
J 0
(-5925 3000);
DISPLAY 0.872340 (-5925 3000);
DISPLAY INVISIBLE (-5925 3000);
FORCEPROP 1 LAST PATH I225
J 0
(-6252 3125);
DISPLAY 0.872340 (-6252 3125);
PAINT GREEN (-6252 3125);
DISPLAY INVISIBLE (-6252 3125);
FORCEADD TAP..1
(-6250 3375);
FORCEPROP 3 LASTPIN (-6300 3375) SIG_NAME M_B_CPU0_SB_DQ<21>
J 0
(-6290 3385);
DISPLAY 0.659574 (-6290 3385);
PAINT MONO (-6290 3385);
DISPLAY INVISIBLE (-6290 3385);
FORCEPROP 1 LASTPIN (-6300 3375) BN 21
J 0
(-6312 3383);
DISPLAY 0.489362 (-6312 3383);
PAINT GREEN (-6312 3383);
FORCEPROP 2 LAST CDS_LIB mstr_standard
J 0
(-6250 3375);
DISPLAY 0.723404 (-6250 3375);
PAINT MONO (-6250 3375);
DISPLAY INVISIBLE (-6250 3375);
FORCEPROP 1 LAST BODY_TYPE PLUMBING
J 0
(-6250 3425);
DISPLAY 0.872340 (-6250 3425);
PAINT GREEN (-6250 3425);
DISPLAY INVISIBLE (-6250 3425);
FORCEPROP 1 LAST HDL_TAP TRUE
J 0
(-5925 3250);
DISPLAY 0.872340 (-5925 3250);
DISPLAY INVISIBLE (-5925 3250);
FORCEPROP 1 LAST PATH I226
J 0
(-6252 3375);
DISPLAY 0.872340 (-6252 3375);
PAINT GREEN (-6252 3375);
DISPLAY INVISIBLE (-6252 3375);
FORCEADD TAP..1
(-6250 3425);
FORCEPROP 3 LASTPIN (-6300 3425) SIG_NAME M_B_CPU0_SB_DQ<22>
J 0
(-6290 3435);
DISPLAY 0.659574 (-6290 3435);
PAINT MONO (-6290 3435);
DISPLAY INVISIBLE (-6290 3435);
FORCEPROP 1 LASTPIN (-6300 3425) BN 22
J 0
(-6312 3433);
DISPLAY 0.489362 (-6312 3433);
PAINT GREEN (-6312 3433);
FORCEPROP 2 LAST CDS_LIB mstr_standard
J 0
(-6250 3425);
DISPLAY 0.723404 (-6250 3425);
PAINT MONO (-6250 3425);
DISPLAY INVISIBLE (-6250 3425);
FORCEPROP 1 LAST BODY_TYPE PLUMBING
J 0
(-6250 3475);
DISPLAY 0.872340 (-6250 3475);
PAINT GREEN (-6250 3475);
DISPLAY INVISIBLE (-6250 3475);
FORCEPROP 1 LAST HDL_TAP TRUE
J 0
(-5925 3300);
DISPLAY 0.872340 (-5925 3300);
DISPLAY INVISIBLE (-5925 3300);
FORCEPROP 1 LAST PATH I227
J 0
(-6252 3425);
DISPLAY 0.872340 (-6252 3425);
PAINT GREEN (-6252 3425);
DISPLAY INVISIBLE (-6252 3425);
FORCEADD TAP..1
(-6250 3325);
FORCEPROP 3 LASTPIN (-6300 3325) SIG_NAME M_B_CPU0_SB_DQ<20>
J 0
(-6290 3335);
DISPLAY 0.659574 (-6290 3335);
PAINT MONO (-6290 3335);
DISPLAY INVISIBLE (-6290 3335);
FORCEPROP 1 LASTPIN (-6300 3325) BN 20
J 0
(-6312 3333);
DISPLAY 0.489362 (-6312 3333);
PAINT GREEN (-6312 3333);
FORCEPROP 2 LAST CDS_LIB mstr_standard
J 0
(-6250 3325);
DISPLAY 0.723404 (-6250 3325);
PAINT MONO (-6250 3325);
DISPLAY INVISIBLE (-6250 3325);
FORCEPROP 1 LAST BODY_TYPE PLUMBING
J 0
(-6250 3375);
DISPLAY 0.872340 (-6250 3375);
PAINT GREEN (-6250 3375);
DISPLAY INVISIBLE (-6250 3375);
FORCEPROP 1 LAST HDL_TAP TRUE
J 0
(-5925 3200);
DISPLAY 0.872340 (-5925 3200);
DISPLAY INVISIBLE (-5925 3200);
FORCEPROP 1 LAST PATH I228
J 0
(-6252 3325);
DISPLAY 0.872340 (-6252 3325);
PAINT GREEN (-6252 3325);
DISPLAY INVISIBLE (-6252 3325);
FORCEADD TAP..1
(-6250 3475);
FORCEPROP 3 LASTPIN (-6300 3475) SIG_NAME M_B_CPU0_SB_DQ<23>
J 0
(-6290 3485);
DISPLAY 0.659574 (-6290 3485);
PAINT MONO (-6290 3485);
DISPLAY INVISIBLE (-6290 3485);
FORCEPROP 1 LASTPIN (-6300 3475) BN 23
J 0
(-6312 3483);
DISPLAY 0.489362 (-6312 3483);
PAINT GREEN (-6312 3483);
FORCEPROP 2 LAST CDS_LIB mstr_standard
J 0
(-6250 3475);
DISPLAY 0.723404 (-6250 3475);
PAINT MONO (-6250 3475);
DISPLAY INVISIBLE (-6250 3475);
FORCEPROP 1 LAST BODY_TYPE PLUMBING
J 0
(-6250 3525);
DISPLAY 0.872340 (-6250 3525);
PAINT GREEN (-6250 3525);
DISPLAY INVISIBLE (-6250 3525);
FORCEPROP 1 LAST HDL_TAP TRUE
J 0
(-5925 3350);
DISPLAY 0.872340 (-5925 3350);
DISPLAY INVISIBLE (-5925 3350);
FORCEPROP 1 LAST PATH I229
J 0
(-6252 3475);
DISPLAY 0.872340 (-6252 3475);
PAINT GREEN (-6252 3475);
DISPLAY INVISIBLE (-6252 3475);
FORCEADD TAP..1
(-6250 3275);
FORCEPROP 3 LASTPIN (-6300 3275) SIG_NAME M_B_CPU0_SB_DQ<19>
J 0
(-6290 3285);
DISPLAY 0.659574 (-6290 3285);
PAINT MONO (-6290 3285);
DISPLAY INVISIBLE (-6290 3285);
FORCEPROP 1 LASTPIN (-6300 3275) BN 19
J 0
(-6312 3283);
DISPLAY 0.489362 (-6312 3283);
PAINT GREEN (-6312 3283);
FORCEPROP 2 LAST CDS_LIB mstr_standard
J 0
(-6250 3275);
DISPLAY 0.723404 (-6250 3275);
PAINT MONO (-6250 3275);
DISPLAY INVISIBLE (-6250 3275);
FORCEPROP 1 LAST BODY_TYPE PLUMBING
J 0
(-6250 3325);
DISPLAY 0.872340 (-6250 3325);
PAINT GREEN (-6250 3325);
DISPLAY INVISIBLE (-6250 3325);
FORCEPROP 1 LAST HDL_TAP TRUE
J 0
(-5925 3150);
DISPLAY 0.872340 (-5925 3150);
DISPLAY INVISIBLE (-5925 3150);
FORCEPROP 1 LAST PATH I230
J 0
(-6252 3275);
DISPLAY 0.872340 (-6252 3275);
PAINT GREEN (-6252 3275);
DISPLAY INVISIBLE (-6252 3275);
FORCEADD TAP..1
(-6250 3625);
FORCEPROP 3 LASTPIN (-6300 3625) SIG_NAME M_B_CPU0_SB_DQ<26>
J 0
(-6290 3635);
DISPLAY 0.659574 (-6290 3635);
PAINT MONO (-6290 3635);
DISPLAY INVISIBLE (-6290 3635);
FORCEPROP 1 LASTPIN (-6300 3625) BN 26
J 0
(-6312 3633);
DISPLAY 0.489362 (-6312 3633);
PAINT GREEN (-6312 3633);
FORCEPROP 2 LAST CDS_LIB mstr_standard
J 0
(-6250 3625);
DISPLAY 0.723404 (-6250 3625);
PAINT MONO (-6250 3625);
DISPLAY INVISIBLE (-6250 3625);
FORCEPROP 1 LAST BODY_TYPE PLUMBING
J 0
(-6250 3675);
DISPLAY 0.872340 (-6250 3675);
PAINT GREEN (-6250 3675);
DISPLAY INVISIBLE (-6250 3675);
FORCEPROP 1 LAST HDL_TAP TRUE
J 0
(-5925 3500);
DISPLAY 0.872340 (-5925 3500);
DISPLAY INVISIBLE (-5925 3500);
FORCEPROP 1 LAST PATH I231
J 0
(-6252 3625);
DISPLAY 0.872340 (-6252 3625);
PAINT GREEN (-6252 3625);
DISPLAY INVISIBLE (-6252 3625);
FORCEADD TAP..1
(-6250 3675);
FORCEPROP 3 LASTPIN (-6300 3675) SIG_NAME M_B_CPU0_SB_DQ<27>
J 0
(-6290 3685);
DISPLAY 0.659574 (-6290 3685);
PAINT MONO (-6290 3685);
DISPLAY INVISIBLE (-6290 3685);
FORCEPROP 1 LASTPIN (-6300 3675) BN 27
J 0
(-6312 3683);
DISPLAY 0.489362 (-6312 3683);
PAINT GREEN (-6312 3683);
FORCEPROP 2 LAST CDS_LIB mstr_standard
J 0
(-6250 3675);
DISPLAY 0.723404 (-6250 3675);
PAINT MONO (-6250 3675);
DISPLAY INVISIBLE (-6250 3675);
FORCEPROP 1 LAST BODY_TYPE PLUMBING
J 0
(-6250 3725);
DISPLAY 0.872340 (-6250 3725);
PAINT GREEN (-6250 3725);
DISPLAY INVISIBLE (-6250 3725);
FORCEPROP 1 LAST HDL_TAP TRUE
J 0
(-5925 3550);
DISPLAY 0.872340 (-5925 3550);
DISPLAY INVISIBLE (-5925 3550);
FORCEPROP 1 LAST PATH I232
J 0
(-6252 3675);
DISPLAY 0.872340 (-6252 3675);
PAINT GREEN (-6252 3675);
DISPLAY INVISIBLE (-6252 3675);
FORCEADD TAP..1
(-6250 3575);
FORCEPROP 3 LASTPIN (-6300 3575) SIG_NAME M_B_CPU0_SB_DQ<25>
J 0
(-6290 3585);
DISPLAY 0.659574 (-6290 3585);
PAINT MONO (-6290 3585);
DISPLAY INVISIBLE (-6290 3585);
FORCEPROP 1 LASTPIN (-6300 3575) BN 25
J 0
(-6312 3583);
DISPLAY 0.489362 (-6312 3583);
PAINT GREEN (-6312 3583);
FORCEPROP 2 LAST CDS_LIB mstr_standard
J 0
(-6250 3575);
DISPLAY 0.723404 (-6250 3575);
PAINT MONO (-6250 3575);
DISPLAY INVISIBLE (-6250 3575);
FORCEPROP 1 LAST BODY_TYPE PLUMBING
J 0
(-6250 3625);
DISPLAY 0.872340 (-6250 3625);
PAINT GREEN (-6250 3625);
DISPLAY INVISIBLE (-6250 3625);
FORCEPROP 1 LAST HDL_TAP TRUE
J 0
(-5925 3450);
DISPLAY 0.872340 (-5925 3450);
DISPLAY INVISIBLE (-5925 3450);
FORCEPROP 1 LAST PATH I233
J 0
(-6252 3575);
DISPLAY 0.872340 (-6252 3575);
PAINT GREEN (-6252 3575);
DISPLAY INVISIBLE (-6252 3575);
FORCEADD TAP..1
(-6250 3725);
FORCEPROP 3 LASTPIN (-6300 3725) SIG_NAME M_B_CPU0_SB_DQ<28>
J 0
(-6290 3735);
DISPLAY 0.659574 (-6290 3735);
PAINT MONO (-6290 3735);
DISPLAY INVISIBLE (-6290 3735);
FORCEPROP 1 LASTPIN (-6300 3725) BN 28
J 0
(-6312 3733);
DISPLAY 0.489362 (-6312 3733);
PAINT GREEN (-6312 3733);
FORCEPROP 2 LAST CDS_LIB mstr_standard
J 0
(-6250 3725);
DISPLAY 0.723404 (-6250 3725);
PAINT MONO (-6250 3725);
DISPLAY INVISIBLE (-6250 3725);
FORCEPROP 1 LAST BODY_TYPE PLUMBING
J 0
(-6250 3775);
DISPLAY 0.872340 (-6250 3775);
PAINT GREEN (-6250 3775);
DISPLAY INVISIBLE (-6250 3775);
FORCEPROP 1 LAST HDL_TAP TRUE
J 0
(-5925 3600);
DISPLAY 0.872340 (-5925 3600);
DISPLAY INVISIBLE (-5925 3600);
FORCEPROP 1 LAST PATH I234
J 0
(-6252 3725);
DISPLAY 0.872340 (-6252 3725);
PAINT GREEN (-6252 3725);
DISPLAY INVISIBLE (-6252 3725);
FORCEADD TAP..1
(-6250 3525);
FORCEPROP 3 LASTPIN (-6300 3525) SIG_NAME M_B_CPU0_SB_DQ<24>
J 0
(-6290 3535);
DISPLAY 0.659574 (-6290 3535);
PAINT MONO (-6290 3535);
DISPLAY INVISIBLE (-6290 3535);
FORCEPROP 1 LASTPIN (-6300 3525) BN 24
J 0
(-6312 3533);
DISPLAY 0.489362 (-6312 3533);
PAINT GREEN (-6312 3533);
FORCEPROP 2 LAST CDS_LIB mstr_standard
J 0
(-6250 3525);
DISPLAY 0.723404 (-6250 3525);
PAINT MONO (-6250 3525);
DISPLAY INVISIBLE (-6250 3525);
FORCEPROP 1 LAST BODY_TYPE PLUMBING
J 0
(-6250 3575);
DISPLAY 0.872340 (-6250 3575);
PAINT GREEN (-6250 3575);
DISPLAY INVISIBLE (-6250 3575);
FORCEPROP 1 LAST HDL_TAP TRUE
J 0
(-5925 3400);
DISPLAY 0.872340 (-5925 3400);
DISPLAY INVISIBLE (-5925 3400);
FORCEPROP 1 LAST PATH I235
J 0
(-6252 3525);
DISPLAY 0.872340 (-6252 3525);
PAINT GREEN (-6252 3525);
DISPLAY INVISIBLE (-6252 3525);
FORCEADD TAP..1
(-6250 3975);
FORCEPROP 3 LASTPIN (-6300 3975) SIG_NAME M_B_CPU0_SA_DQ<0>
J 0
(-6290 3985);
DISPLAY 0.659574 (-6290 3985);
PAINT MONO (-6290 3985);
DISPLAY INVISIBLE (-6290 3985);
FORCEPROP 1 LASTPIN (-6300 3975) BN 0
J 0
(-6312 3983);
DISPLAY 0.489362 (-6312 3983);
PAINT GREEN (-6312 3983);
FORCEPROP 2 LAST CDS_LIB mstr_standard
J 0
(-6250 3975);
DISPLAY 0.723404 (-6250 3975);
PAINT MONO (-6250 3975);
DISPLAY INVISIBLE (-6250 3975);
FORCEPROP 1 LAST BODY_TYPE PLUMBING
J 0
(-6250 4025);
DISPLAY 0.872340 (-6250 4025);
PAINT GREEN (-6250 4025);
DISPLAY INVISIBLE (-6250 4025);
FORCEPROP 1 LAST HDL_TAP TRUE
J 0
(-5925 3850);
DISPLAY 0.872340 (-5925 3850);
DISPLAY INVISIBLE (-5925 3850);
FORCEPROP 1 LAST PATH I236
J 0
(-6252 3975);
DISPLAY 0.872340 (-6252 3975);
PAINT GREEN (-6252 3975);
DISPLAY INVISIBLE (-6252 3975);
FORCEADD TAP..1
(-6250 3825);
FORCEPROP 3 LASTPIN (-6300 3825) SIG_NAME M_B_CPU0_SB_DQ<30>
J 0
(-6290 3835);
DISPLAY 0.659574 (-6290 3835);
PAINT MONO (-6290 3835);
DISPLAY INVISIBLE (-6290 3835);
FORCEPROP 1 LASTPIN (-6300 3825) BN 30
J 0
(-6312 3833);
DISPLAY 0.489362 (-6312 3833);
PAINT GREEN (-6312 3833);
FORCEPROP 2 LAST CDS_LIB mstr_standard
J 0
(-6250 3825);
DISPLAY 0.723404 (-6250 3825);
PAINT MONO (-6250 3825);
DISPLAY INVISIBLE (-6250 3825);
FORCEPROP 1 LAST BODY_TYPE PLUMBING
J 0
(-6250 3875);
DISPLAY 0.872340 (-6250 3875);
PAINT GREEN (-6250 3875);
DISPLAY INVISIBLE (-6250 3875);
FORCEPROP 1 LAST HDL_TAP TRUE
J 0
(-5925 3700);
DISPLAY 0.872340 (-5925 3700);
DISPLAY INVISIBLE (-5925 3700);
FORCEPROP 1 LAST PATH I237
J 0
(-6252 3825);
DISPLAY 0.872340 (-6252 3825);
PAINT GREEN (-6252 3825);
DISPLAY INVISIBLE (-6252 3825);
FORCEADD TAP..1
(-6250 3875);
FORCEPROP 3 LASTPIN (-6300 3875) SIG_NAME M_B_CPU0_SB_DQ<31>
J 0
(-6290 3885);
DISPLAY 0.659574 (-6290 3885);
PAINT MONO (-6290 3885);
DISPLAY INVISIBLE (-6290 3885);
FORCEPROP 1 LASTPIN (-6300 3875) BN 31
J 0
(-6312 3883);
DISPLAY 0.489362 (-6312 3883);
PAINT GREEN (-6312 3883);
FORCEPROP 2 LAST CDS_LIB mstr_standard
J 0
(-6250 3875);
DISPLAY 0.723404 (-6250 3875);
PAINT MONO (-6250 3875);
DISPLAY INVISIBLE (-6250 3875);
FORCEPROP 1 LAST BODY_TYPE PLUMBING
J 0
(-6250 3925);
DISPLAY 0.872340 (-6250 3925);
PAINT GREEN (-6250 3925);
DISPLAY INVISIBLE (-6250 3925);
FORCEPROP 1 LAST HDL_TAP TRUE
J 0
(-5925 3750);
DISPLAY 0.872340 (-5925 3750);
DISPLAY INVISIBLE (-5925 3750);
FORCEPROP 1 LAST PATH I238
J 0
(-6252 3875);
DISPLAY 0.872340 (-6252 3875);
PAINT GREEN (-6252 3875);
DISPLAY INVISIBLE (-6252 3875);
FORCEADD TAP..1
(-6250 3775);
FORCEPROP 3 LASTPIN (-6300 3775) SIG_NAME M_B_CPU0_SB_DQ<29>
J 0
(-6290 3785);
DISPLAY 0.659574 (-6290 3785);
PAINT MONO (-6290 3785);
DISPLAY INVISIBLE (-6290 3785);
FORCEPROP 1 LASTPIN (-6300 3775) BN 29
J 0
(-6312 3783);
DISPLAY 0.489362 (-6312 3783);
PAINT GREEN (-6312 3783);
FORCEPROP 2 LAST CDS_LIB mstr_standard
J 0
(-6250 3775);
DISPLAY 0.723404 (-6250 3775);
PAINT MONO (-6250 3775);
DISPLAY INVISIBLE (-6250 3775);
FORCEPROP 1 LAST BODY_TYPE PLUMBING
J 0
(-6250 3825);
DISPLAY 0.872340 (-6250 3825);
PAINT GREEN (-6250 3825);
DISPLAY INVISIBLE (-6250 3825);
FORCEPROP 1 LAST HDL_TAP TRUE
J 0
(-5925 3650);
DISPLAY 0.872340 (-5925 3650);
DISPLAY INVISIBLE (-5925 3650);
FORCEPROP 1 LAST PATH I239
J 0
(-6252 3775);
DISPLAY 0.872340 (-6252 3775);
PAINT GREEN (-6252 3775);
DISPLAY INVISIBLE (-6252 3775);
FORCEADD TAP..1
(-6250 4075);
FORCEPROP 3 LASTPIN (-6300 4075) SIG_NAME M_B_CPU0_SA_DQ<2>
J 0
(-6290 4085);
DISPLAY 0.659574 (-6290 4085);
PAINT MONO (-6290 4085);
DISPLAY INVISIBLE (-6290 4085);
FORCEPROP 1 LASTPIN (-6300 4075) BN 2
J 0
(-6312 4083);
DISPLAY 0.489362 (-6312 4083);
PAINT GREEN (-6312 4083);
FORCEPROP 2 LAST CDS_LIB mstr_standard
J 0
(-6250 4075);
DISPLAY 0.723404 (-6250 4075);
PAINT MONO (-6250 4075);
DISPLAY INVISIBLE (-6250 4075);
FORCEPROP 1 LAST BODY_TYPE PLUMBING
J 0
(-6250 4125);
DISPLAY 0.872340 (-6250 4125);
PAINT GREEN (-6250 4125);
DISPLAY INVISIBLE (-6250 4125);
FORCEPROP 1 LAST HDL_TAP TRUE
J 0
(-5925 3950);
DISPLAY 0.872340 (-5925 3950);
DISPLAY INVISIBLE (-5925 3950);
FORCEPROP 1 LAST PATH I240
J 0
(-6252 4075);
DISPLAY 0.872340 (-6252 4075);
PAINT GREEN (-6252 4075);
DISPLAY INVISIBLE (-6252 4075);
FORCEADD TAP..1
(-6250 4025);
FORCEPROP 3 LASTPIN (-6300 4025) SIG_NAME M_B_CPU0_SA_DQ<1>
J 0
(-6290 4035);
DISPLAY 0.659574 (-6290 4035);
PAINT MONO (-6290 4035);
DISPLAY INVISIBLE (-6290 4035);
FORCEPROP 1 LASTPIN (-6300 4025) BN 1
J 0
(-6312 4033);
DISPLAY 0.489362 (-6312 4033);
PAINT GREEN (-6312 4033);
FORCEPROP 2 LAST CDS_LIB mstr_standard
J 0
(-6250 4025);
DISPLAY 0.723404 (-6250 4025);
PAINT MONO (-6250 4025);
DISPLAY INVISIBLE (-6250 4025);
FORCEPROP 1 LAST BODY_TYPE PLUMBING
J 0
(-6250 4075);
DISPLAY 0.872340 (-6250 4075);
PAINT GREEN (-6250 4075);
DISPLAY INVISIBLE (-6250 4075);
FORCEPROP 1 LAST HDL_TAP TRUE
J 0
(-5925 3900);
DISPLAY 0.872340 (-5925 3900);
DISPLAY INVISIBLE (-5925 3900);
FORCEPROP 1 LAST PATH I241
J 0
(-6252 4025);
DISPLAY 0.872340 (-6252 4025);
PAINT GREEN (-6252 4025);
DISPLAY INVISIBLE (-6252 4025);
FORCEADD TAP..1
(-6250 4125);
FORCEPROP 3 LASTPIN (-6300 4125) SIG_NAME M_B_CPU0_SA_DQ<3>
J 0
(-6290 4135);
DISPLAY 0.659574 (-6290 4135);
PAINT MONO (-6290 4135);
DISPLAY INVISIBLE (-6290 4135);
FORCEPROP 1 LASTPIN (-6300 4125) BN 3
J 0
(-6312 4133);
DISPLAY 0.489362 (-6312 4133);
PAINT GREEN (-6312 4133);
FORCEPROP 2 LAST CDS_LIB mstr_standard
J 0
(-6250 4125);
DISPLAY 0.723404 (-6250 4125);
PAINT MONO (-6250 4125);
DISPLAY INVISIBLE (-6250 4125);
FORCEPROP 1 LAST BODY_TYPE PLUMBING
J 0
(-6250 4175);
DISPLAY 0.872340 (-6250 4175);
PAINT GREEN (-6250 4175);
DISPLAY INVISIBLE (-6250 4175);
FORCEPROP 1 LAST HDL_TAP TRUE
J 0
(-5925 4000);
DISPLAY 0.872340 (-5925 4000);
DISPLAY INVISIBLE (-5925 4000);
FORCEPROP 1 LAST PATH I242
J 0
(-6252 4125);
DISPLAY 0.872340 (-6252 4125);
PAINT GREEN (-6252 4125);
DISPLAY INVISIBLE (-6252 4125);
FORCEADD TAP..1
(-6250 4175);
FORCEPROP 3 LASTPIN (-6300 4175) SIG_NAME M_B_CPU0_SA_DQ<4>
J 0
(-6290 4185);
DISPLAY 0.659574 (-6290 4185);
PAINT MONO (-6290 4185);
DISPLAY INVISIBLE (-6290 4185);
FORCEPROP 1 LASTPIN (-6300 4175) BN 4
J 0
(-6312 4183);
DISPLAY 0.489362 (-6312 4183);
PAINT GREEN (-6312 4183);
FORCEPROP 2 LAST CDS_LIB mstr_standard
J 0
(-6250 4175);
DISPLAY 0.723404 (-6250 4175);
PAINT MONO (-6250 4175);
DISPLAY INVISIBLE (-6250 4175);
FORCEPROP 1 LAST BODY_TYPE PLUMBING
J 0
(-6250 4225);
DISPLAY 0.872340 (-6250 4225);
PAINT GREEN (-6250 4225);
DISPLAY INVISIBLE (-6250 4225);
FORCEPROP 1 LAST HDL_TAP TRUE
J 0
(-5925 4050);
DISPLAY 0.872340 (-5925 4050);
DISPLAY INVISIBLE (-5925 4050);
FORCEPROP 1 LAST PATH I243
J 0
(-6252 4175);
DISPLAY 0.872340 (-6252 4175);
PAINT GREEN (-6252 4175);
DISPLAY INVISIBLE (-6252 4175);
FORCEADD TAP..1
(-6250 4225);
FORCEPROP 3 LASTPIN (-6300 4225) SIG_NAME M_B_CPU0_SA_DQ<5>
J 0
(-6290 4235);
DISPLAY 0.659574 (-6290 4235);
PAINT MONO (-6290 4235);
DISPLAY INVISIBLE (-6290 4235);
FORCEPROP 1 LASTPIN (-6300 4225) BN 5
J 0
(-6312 4233);
DISPLAY 0.489362 (-6312 4233);
PAINT GREEN (-6312 4233);
FORCEPROP 2 LAST CDS_LIB mstr_standard
J 0
(-6250 4225);
DISPLAY 0.723404 (-6250 4225);
PAINT MONO (-6250 4225);
DISPLAY INVISIBLE (-6250 4225);
FORCEPROP 1 LAST BODY_TYPE PLUMBING
J 0
(-6250 4275);
DISPLAY 0.872340 (-6250 4275);
PAINT GREEN (-6250 4275);
DISPLAY INVISIBLE (-6250 4275);
FORCEPROP 1 LAST HDL_TAP TRUE
J 0
(-5925 4100);
DISPLAY 0.872340 (-5925 4100);
DISPLAY INVISIBLE (-5925 4100);
FORCEPROP 1 LAST PATH I244
J 0
(-6252 4225);
DISPLAY 0.872340 (-6252 4225);
PAINT GREEN (-6252 4225);
DISPLAY INVISIBLE (-6252 4225);
FORCEADD TAP..1
(-6250 4325);
FORCEPROP 3 LASTPIN (-6300 4325) SIG_NAME M_B_CPU0_SA_DQ<7>
J 0
(-6290 4335);
DISPLAY 0.659574 (-6290 4335);
PAINT MONO (-6290 4335);
DISPLAY INVISIBLE (-6290 4335);
FORCEPROP 1 LASTPIN (-6300 4325) BN 7
J 0
(-6312 4333);
DISPLAY 0.489362 (-6312 4333);
PAINT GREEN (-6312 4333);
FORCEPROP 2 LAST CDS_LIB mstr_standard
J 0
(-6250 4325);
DISPLAY 0.723404 (-6250 4325);
PAINT MONO (-6250 4325);
DISPLAY INVISIBLE (-6250 4325);
FORCEPROP 1 LAST BODY_TYPE PLUMBING
J 0
(-6250 4375);
DISPLAY 0.872340 (-6250 4375);
PAINT GREEN (-6250 4375);
DISPLAY INVISIBLE (-6250 4375);
FORCEPROP 1 LAST HDL_TAP TRUE
J 0
(-5925 4200);
DISPLAY 0.872340 (-5925 4200);
DISPLAY INVISIBLE (-5925 4200);
FORCEPROP 1 LAST PATH I245
J 0
(-6252 4325);
DISPLAY 0.872340 (-6252 4325);
PAINT GREEN (-6252 4325);
DISPLAY INVISIBLE (-6252 4325);
FORCEADD TAP..1
(-6250 4275);
FORCEPROP 3 LASTPIN (-6300 4275) SIG_NAME M_B_CPU0_SA_DQ<6>
J 0
(-6290 4285);
DISPLAY 0.659574 (-6290 4285);
PAINT MONO (-6290 4285);
DISPLAY INVISIBLE (-6290 4285);
FORCEPROP 1 LASTPIN (-6300 4275) BN 6
J 0
(-6312 4283);
DISPLAY 0.489362 (-6312 4283);
PAINT GREEN (-6312 4283);
FORCEPROP 2 LAST CDS_LIB mstr_standard
J 0
(-6250 4275);
DISPLAY 0.723404 (-6250 4275);
PAINT MONO (-6250 4275);
DISPLAY INVISIBLE (-6250 4275);
FORCEPROP 1 LAST BODY_TYPE PLUMBING
J 0
(-6250 4325);
DISPLAY 0.872340 (-6250 4325);
PAINT GREEN (-6250 4325);
DISPLAY INVISIBLE (-6250 4325);
FORCEPROP 1 LAST HDL_TAP TRUE
J 0
(-5925 4150);
DISPLAY 0.872340 (-5925 4150);
DISPLAY INVISIBLE (-5925 4150);
FORCEPROP 1 LAST PATH I246
J 0
(-6252 4275);
DISPLAY 0.872340 (-6252 4275);
PAINT GREEN (-6252 4275);
DISPLAY INVISIBLE (-6252 4275);
FORCEADD TAP..1
(-6250 4375);
FORCEPROP 3 LASTPIN (-6300 4375) SIG_NAME M_B_CPU0_SA_DQ<8>
J 0
(-6290 4385);
DISPLAY 0.659574 (-6290 4385);
PAINT MONO (-6290 4385);
DISPLAY INVISIBLE (-6290 4385);
FORCEPROP 1 LASTPIN (-6300 4375) BN 8
J 0
(-6312 4383);
DISPLAY 0.489362 (-6312 4383);
PAINT GREEN (-6312 4383);
FORCEPROP 2 LAST CDS_LIB mstr_standard
J 0
(-6250 4375);
DISPLAY 0.723404 (-6250 4375);
PAINT MONO (-6250 4375);
DISPLAY INVISIBLE (-6250 4375);
FORCEPROP 1 LAST BODY_TYPE PLUMBING
J 0
(-6250 4425);
DISPLAY 0.872340 (-6250 4425);
PAINT GREEN (-6250 4425);
DISPLAY INVISIBLE (-6250 4425);
FORCEPROP 1 LAST HDL_TAP TRUE
J 0
(-5925 4250);
DISPLAY 0.872340 (-5925 4250);
DISPLAY INVISIBLE (-5925 4250);
FORCEPROP 1 LAST PATH I247
J 0
(-6252 4375);
DISPLAY 0.872340 (-6252 4375);
PAINT GREEN (-6252 4375);
DISPLAY INVISIBLE (-6252 4375);
FORCEADD TAP..1
(-6250 4425);
FORCEPROP 3 LASTPIN (-6300 4425) SIG_NAME M_B_CPU0_SA_DQ<9>
J 0
(-6290 4435);
DISPLAY 0.659574 (-6290 4435);
PAINT MONO (-6290 4435);
DISPLAY INVISIBLE (-6290 4435);
FORCEPROP 1 LASTPIN (-6300 4425) BN 9
J 0
(-6312 4433);
DISPLAY 0.489362 (-6312 4433);
PAINT GREEN (-6312 4433);
FORCEPROP 2 LAST CDS_LIB mstr_standard
J 0
(-6250 4425);
DISPLAY 0.723404 (-6250 4425);
PAINT MONO (-6250 4425);
DISPLAY INVISIBLE (-6250 4425);
FORCEPROP 1 LAST BODY_TYPE PLUMBING
J 0
(-6250 4475);
DISPLAY 0.872340 (-6250 4475);
PAINT GREEN (-6250 4475);
DISPLAY INVISIBLE (-6250 4475);
FORCEPROP 1 LAST HDL_TAP TRUE
J 0
(-5925 4300);
DISPLAY 0.872340 (-5925 4300);
DISPLAY INVISIBLE (-5925 4300);
FORCEPROP 1 LAST PATH I248
J 0
(-6252 4425);
DISPLAY 0.872340 (-6252 4425);
PAINT GREEN (-6252 4425);
DISPLAY INVISIBLE (-6252 4425);
FORCEADD TAP..1
(-6250 4475);
FORCEPROP 3 LASTPIN (-6300 4475) SIG_NAME M_B_CPU0_SA_DQ<10>
J 0
(-6290 4485);
DISPLAY 0.659574 (-6290 4485);
PAINT MONO (-6290 4485);
DISPLAY INVISIBLE (-6290 4485);
FORCEPROP 1 LASTPIN (-6300 4475) BN 10
J 0
(-6312 4483);
DISPLAY 0.489362 (-6312 4483);
PAINT GREEN (-6312 4483);
FORCEPROP 2 LAST CDS_LIB mstr_standard
J 0
(-6250 4475);
DISPLAY 0.723404 (-6250 4475);
PAINT MONO (-6250 4475);
DISPLAY INVISIBLE (-6250 4475);
FORCEPROP 1 LAST BODY_TYPE PLUMBING
J 0
(-6250 4525);
DISPLAY 0.872340 (-6250 4525);
PAINT GREEN (-6250 4525);
DISPLAY INVISIBLE (-6250 4525);
FORCEPROP 1 LAST HDL_TAP TRUE
J 0
(-5925 4350);
DISPLAY 0.872340 (-5925 4350);
DISPLAY INVISIBLE (-5925 4350);
FORCEPROP 1 LAST PATH I249
J 0
(-6252 4475);
DISPLAY 0.872340 (-6252 4475);
PAINT GREEN (-6252 4475);
DISPLAY INVISIBLE (-6252 4475);
FORCEADD TAP..1
(-6250 4675);
FORCEPROP 3 LASTPIN (-6300 4675) SIG_NAME M_B_CPU0_SA_DQ<14>
J 0
(-6290 4685);
DISPLAY 0.659574 (-6290 4685);
PAINT MONO (-6290 4685);
DISPLAY INVISIBLE (-6290 4685);
FORCEPROP 1 LASTPIN (-6300 4675) BN 14
J 0
(-6312 4683);
DISPLAY 0.489362 (-6312 4683);
PAINT GREEN (-6312 4683);
FORCEPROP 2 LAST CDS_LIB mstr_standard
J 0
(-6250 4675);
DISPLAY 0.723404 (-6250 4675);
PAINT MONO (-6250 4675);
DISPLAY INVISIBLE (-6250 4675);
FORCEPROP 1 LAST BODY_TYPE PLUMBING
J 0
(-6250 4725);
DISPLAY 0.872340 (-6250 4725);
PAINT GREEN (-6250 4725);
DISPLAY INVISIBLE (-6250 4725);
FORCEPROP 1 LAST HDL_TAP TRUE
J 0
(-5925 4550);
DISPLAY 0.872340 (-5925 4550);
DISPLAY INVISIBLE (-5925 4550);
FORCEPROP 1 LAST PATH I250
J 0
(-6252 4675);
DISPLAY 0.872340 (-6252 4675);
PAINT GREEN (-6252 4675);
DISPLAY INVISIBLE (-6252 4675);
FORCEADD TAP..1
(-6250 4725);
FORCEPROP 3 LASTPIN (-6300 4725) SIG_NAME M_B_CPU0_SA_DQ<15>
J 0
(-6290 4735);
DISPLAY 0.659574 (-6290 4735);
PAINT MONO (-6290 4735);
DISPLAY INVISIBLE (-6290 4735);
FORCEPROP 1 LASTPIN (-6300 4725) BN 15
J 0
(-6312 4733);
DISPLAY 0.489362 (-6312 4733);
PAINT GREEN (-6312 4733);
FORCEPROP 2 LAST CDS_LIB mstr_standard
J 0
(-6250 4725);
DISPLAY 0.723404 (-6250 4725);
PAINT MONO (-6250 4725);
DISPLAY INVISIBLE (-6250 4725);
FORCEPROP 1 LAST BODY_TYPE PLUMBING
J 0
(-6250 4775);
DISPLAY 0.872340 (-6250 4775);
PAINT GREEN (-6250 4775);
DISPLAY INVISIBLE (-6250 4775);
FORCEPROP 1 LAST HDL_TAP TRUE
J 0
(-5925 4600);
DISPLAY 0.872340 (-5925 4600);
DISPLAY INVISIBLE (-5925 4600);
FORCEPROP 1 LAST PATH I251
J 0
(-6252 4725);
DISPLAY 0.872340 (-6252 4725);
PAINT GREEN (-6252 4725);
DISPLAY INVISIBLE (-6252 4725);
FORCEADD TAP..1
(-6250 4625);
FORCEPROP 3 LASTPIN (-6300 4625) SIG_NAME M_B_CPU0_SA_DQ<13>
J 0
(-6290 4635);
DISPLAY 0.659574 (-6290 4635);
PAINT MONO (-6290 4635);
DISPLAY INVISIBLE (-6290 4635);
FORCEPROP 1 LASTPIN (-6300 4625) BN 13
J 0
(-6312 4633);
DISPLAY 0.489362 (-6312 4633);
PAINT GREEN (-6312 4633);
FORCEPROP 2 LAST CDS_LIB mstr_standard
J 0
(-6250 4625);
DISPLAY 0.723404 (-6250 4625);
PAINT MONO (-6250 4625);
DISPLAY INVISIBLE (-6250 4625);
FORCEPROP 1 LAST BODY_TYPE PLUMBING
J 0
(-6250 4675);
DISPLAY 0.872340 (-6250 4675);
PAINT GREEN (-6250 4675);
DISPLAY INVISIBLE (-6250 4675);
FORCEPROP 1 LAST HDL_TAP TRUE
J 0
(-5925 4500);
DISPLAY 0.872340 (-5925 4500);
DISPLAY INVISIBLE (-5925 4500);
FORCEPROP 1 LAST PATH I252
J 0
(-6252 4625);
DISPLAY 0.872340 (-6252 4625);
PAINT GREEN (-6252 4625);
DISPLAY INVISIBLE (-6252 4625);
FORCEADD TAP..1
(-6250 4575);
FORCEPROP 3 LASTPIN (-6300 4575) SIG_NAME M_B_CPU0_SA_DQ<12>
J 0
(-6290 4585);
DISPLAY 0.659574 (-6290 4585);
PAINT MONO (-6290 4585);
DISPLAY INVISIBLE (-6290 4585);
FORCEPROP 1 LASTPIN (-6300 4575) BN 12
J 0
(-6312 4583);
DISPLAY 0.489362 (-6312 4583);
PAINT GREEN (-6312 4583);
FORCEPROP 2 LAST CDS_LIB mstr_standard
J 0
(-6250 4575);
DISPLAY 0.723404 (-6250 4575);
PAINT MONO (-6250 4575);
DISPLAY INVISIBLE (-6250 4575);
FORCEPROP 1 LAST BODY_TYPE PLUMBING
J 0
(-6250 4625);
DISPLAY 0.872340 (-6250 4625);
PAINT GREEN (-6250 4625);
DISPLAY INVISIBLE (-6250 4625);
FORCEPROP 1 LAST HDL_TAP TRUE
J 0
(-5925 4450);
DISPLAY 0.872340 (-5925 4450);
DISPLAY INVISIBLE (-5925 4450);
FORCEPROP 1 LAST PATH I253
J 0
(-6252 4575);
DISPLAY 0.872340 (-6252 4575);
PAINT GREEN (-6252 4575);
DISPLAY INVISIBLE (-6252 4575);
FORCEADD TAP..1
(-6250 4525);
FORCEPROP 3 LASTPIN (-6300 4525) SIG_NAME M_B_CPU0_SA_DQ<11>
J 0
(-6290 4535);
DISPLAY 0.659574 (-6290 4535);
PAINT MONO (-6290 4535);
DISPLAY INVISIBLE (-6290 4535);
FORCEPROP 1 LASTPIN (-6300 4525) BN 11
J 0
(-6312 4533);
DISPLAY 0.489362 (-6312 4533);
PAINT GREEN (-6312 4533);
FORCEPROP 2 LAST CDS_LIB mstr_standard
J 0
(-6250 4525);
DISPLAY 0.723404 (-6250 4525);
PAINT MONO (-6250 4525);
DISPLAY INVISIBLE (-6250 4525);
FORCEPROP 1 LAST BODY_TYPE PLUMBING
J 0
(-6250 4575);
DISPLAY 0.872340 (-6250 4575);
PAINT GREEN (-6250 4575);
DISPLAY INVISIBLE (-6250 4575);
FORCEPROP 1 LAST HDL_TAP TRUE
J 0
(-5925 4400);
DISPLAY 0.872340 (-5925 4400);
DISPLAY INVISIBLE (-5925 4400);
FORCEPROP 1 LAST PATH I254
J 0
(-6252 4525);
DISPLAY 0.872340 (-6252 4525);
PAINT GREEN (-6252 4525);
DISPLAY INVISIBLE (-6252 4525);
FORCEADD TAP..1
(-6250 4825);
FORCEPROP 3 LASTPIN (-6300 4825) SIG_NAME M_B_CPU0_SA_DQ<17>
J 0
(-6290 4835);
DISPLAY 0.659574 (-6290 4835);
PAINT MONO (-6290 4835);
DISPLAY INVISIBLE (-6290 4835);
FORCEPROP 1 LASTPIN (-6300 4825) BN 17
J 0
(-6312 4833);
DISPLAY 0.489362 (-6312 4833);
PAINT GREEN (-6312 4833);
FORCEPROP 2 LAST CDS_LIB mstr_standard
J 0
(-6250 4825);
DISPLAY 0.723404 (-6250 4825);
PAINT MONO (-6250 4825);
DISPLAY INVISIBLE (-6250 4825);
FORCEPROP 1 LAST BODY_TYPE PLUMBING
J 0
(-6250 4875);
DISPLAY 0.872340 (-6250 4875);
PAINT GREEN (-6250 4875);
DISPLAY INVISIBLE (-6250 4875);
FORCEPROP 1 LAST HDL_TAP TRUE
J 0
(-5925 4700);
DISPLAY 0.872340 (-5925 4700);
DISPLAY INVISIBLE (-5925 4700);
FORCEPROP 1 LAST PATH I255
J 0
(-6252 4825);
DISPLAY 0.872340 (-6252 4825);
PAINT GREEN (-6252 4825);
DISPLAY INVISIBLE (-6252 4825);
FORCEADD TAP..1
(-6250 4875);
FORCEPROP 3 LASTPIN (-6300 4875) SIG_NAME M_B_CPU0_SA_DQ<18>
J 0
(-6290 4885);
DISPLAY 0.659574 (-6290 4885);
PAINT MONO (-6290 4885);
DISPLAY INVISIBLE (-6290 4885);
FORCEPROP 1 LASTPIN (-6300 4875) BN 18
J 0
(-6312 4883);
DISPLAY 0.489362 (-6312 4883);
PAINT GREEN (-6312 4883);
FORCEPROP 2 LAST CDS_LIB mstr_standard
J 0
(-6250 4875);
DISPLAY 0.723404 (-6250 4875);
PAINT MONO (-6250 4875);
DISPLAY INVISIBLE (-6250 4875);
FORCEPROP 1 LAST BODY_TYPE PLUMBING
J 0
(-6250 4925);
DISPLAY 0.872340 (-6250 4925);
PAINT GREEN (-6250 4925);
DISPLAY INVISIBLE (-6250 4925);
FORCEPROP 1 LAST HDL_TAP TRUE
J 0
(-5925 4750);
DISPLAY 0.872340 (-5925 4750);
DISPLAY INVISIBLE (-5925 4750);
FORCEPROP 1 LAST PATH I256
J 0
(-6252 4875);
DISPLAY 0.872340 (-6252 4875);
PAINT GREEN (-6252 4875);
DISPLAY INVISIBLE (-6252 4875);
FORCEADD TAP..1
(-6250 4775);
FORCEPROP 3 LASTPIN (-6300 4775) SIG_NAME M_B_CPU0_SA_DQ<16>
J 0
(-6290 4785);
DISPLAY 0.659574 (-6290 4785);
PAINT MONO (-6290 4785);
DISPLAY INVISIBLE (-6290 4785);
FORCEPROP 1 LASTPIN (-6300 4775) BN 16
J 0
(-6312 4783);
DISPLAY 0.489362 (-6312 4783);
PAINT GREEN (-6312 4783);
FORCEPROP 2 LAST CDS_LIB mstr_standard
J 0
(-6250 4775);
DISPLAY 0.723404 (-6250 4775);
PAINT MONO (-6250 4775);
DISPLAY INVISIBLE (-6250 4775);
FORCEPROP 1 LAST BODY_TYPE PLUMBING
J 0
(-6250 4825);
DISPLAY 0.872340 (-6250 4825);
PAINT GREEN (-6250 4825);
DISPLAY INVISIBLE (-6250 4825);
FORCEPROP 1 LAST HDL_TAP TRUE
J 0
(-5925 4650);
DISPLAY 0.872340 (-5925 4650);
DISPLAY INVISIBLE (-5925 4650);
FORCEPROP 1 LAST PATH I257
J 0
(-6252 4775);
DISPLAY 0.872340 (-6252 4775);
PAINT GREEN (-6252 4775);
DISPLAY INVISIBLE (-6252 4775);
FORCEADD TAP..1
(-6250 4975);
FORCEPROP 3 LASTPIN (-6300 4975) SIG_NAME M_B_CPU0_SA_DQ<20>
J 0
(-6290 4985);
DISPLAY 0.659574 (-6290 4985);
PAINT MONO (-6290 4985);
DISPLAY INVISIBLE (-6290 4985);
FORCEPROP 1 LASTPIN (-6300 4975) BN 20
J 0
(-6312 4983);
DISPLAY 0.489362 (-6312 4983);
PAINT GREEN (-6312 4983);
FORCEPROP 2 LAST CDS_LIB mstr_standard
J 0
(-6250 4975);
DISPLAY 0.723404 (-6250 4975);
PAINT MONO (-6250 4975);
DISPLAY INVISIBLE (-6250 4975);
FORCEPROP 1 LAST BODY_TYPE PLUMBING
J 0
(-6250 5025);
DISPLAY 0.872340 (-6250 5025);
PAINT GREEN (-6250 5025);
DISPLAY INVISIBLE (-6250 5025);
FORCEPROP 1 LAST HDL_TAP TRUE
J 0
(-5925 4850);
DISPLAY 0.872340 (-5925 4850);
DISPLAY INVISIBLE (-5925 4850);
FORCEPROP 1 LAST PATH I258
J 0
(-6252 4975);
DISPLAY 0.872340 (-6252 4975);
PAINT GREEN (-6252 4975);
DISPLAY INVISIBLE (-6252 4975);
FORCEADD TAP..1
(-6250 4925);
FORCEPROP 3 LASTPIN (-6300 4925) SIG_NAME M_B_CPU0_SA_DQ<19>
J 0
(-6290 4935);
DISPLAY 0.659574 (-6290 4935);
PAINT MONO (-6290 4935);
DISPLAY INVISIBLE (-6290 4935);
FORCEPROP 1 LASTPIN (-6300 4925) BN 19
J 0
(-6312 4933);
DISPLAY 0.489362 (-6312 4933);
PAINT GREEN (-6312 4933);
FORCEPROP 2 LAST CDS_LIB mstr_standard
J 0
(-6250 4925);
DISPLAY 0.723404 (-6250 4925);
PAINT MONO (-6250 4925);
DISPLAY INVISIBLE (-6250 4925);
FORCEPROP 1 LAST BODY_TYPE PLUMBING
J 0
(-6250 4975);
DISPLAY 0.872340 (-6250 4975);
PAINT GREEN (-6250 4975);
DISPLAY INVISIBLE (-6250 4975);
FORCEPROP 1 LAST HDL_TAP TRUE
J 0
(-5925 4800);
DISPLAY 0.872340 (-5925 4800);
DISPLAY INVISIBLE (-5925 4800);
FORCEPROP 1 LAST PATH I259
J 0
(-6252 4925);
DISPLAY 0.872340 (-6252 4925);
PAINT GREEN (-6252 4925);
DISPLAY INVISIBLE (-6252 4925);
FORCEADD OFFPAGE..3
(-5500 3925);
FORCEPROP 2 LAST $XR0 11 
J 0
(-5286 3925);
DISPLAY 0.638298 (-5286 3925);
PAINT MONO (-5286 3925);
FORCEPROP 2 LAST PATH I260
J 0
(-5175 3975);
DISPLAY 0.808511 (-5175 3975);
DISPLAY INVISIBLE (-5175 3975);
FORCEPROP 1 LAST COMMENT_BODY TRUE
J 0
(-5550 3825);
DISPLAY 0.872340 (-5550 3825);
PAINT GREEN (-5550 3825);
DISPLAY INVISIBLE (-5550 3825);
FORCEPROP 1 LAST OFFPAGE TRUE
J 0
(-5175 3800);
DISPLAY 0.872340 (-5175 3800);
PAINT GREEN (-5175 3800);
DISPLAY INVISIBLE (-5175 3800);
FORCEPROP 2 LAST CDS_LIB mstr_standard
J 0
(-5500 3925);
DISPLAY 0.723404 (-5500 3925);
PAINT MONO (-5500 3925);
DISPLAY INVISIBLE (-5500 3925);
FORCEADD OFFPAGE..1
(-8550 5175);
FORCEPROP 2 LAST $XR0 11 
J 0
(-8771 5175);
DISPLAY 0.638298 (-8771 5175);
PAINT MONO (-8771 5175);
FORCEPROP 2 LAST PATH I261
J 0
(-8500 5250);
DISPLAY 0.808511 (-8500 5250);
DISPLAY INVISIBLE (-8500 5250);
FORCEPROP 1 LAST COMMENT_BODY TRUE
J 0
(-8425 5075);
DISPLAY 0.872340 (-8425 5075);
PAINT GREEN (-8425 5075);
DISPLAY INVISIBLE (-8425 5075);
FORCEPROP 1 LAST OFFPAGE TRUE
J 0
(-8225 5050);
DISPLAY 0.872340 (-8225 5050);
PAINT GREEN (-8225 5050);
DISPLAY INVISIBLE (-8225 5050);
FORCEPROP 2 LAST CDS_LIB mstr_standard
J 0
(-8550 5175);
DISPLAY 0.723404 (-8550 5175);
PAINT MONO (-8550 5175);
DISPLAY INVISIBLE (-8550 5175);
FORCEADD OFFPAGE..1
(-8550 5575);
FORCEPROP 2 LAST $XR0 11 
J 0
(-8771 5575);
DISPLAY 0.638298 (-8771 5575);
PAINT MONO (-8771 5575);
FORCEPROP 2 LAST PATH I262
J 0
(-8500 5650);
DISPLAY 0.808511 (-8500 5650);
DISPLAY INVISIBLE (-8500 5650);
FORCEPROP 1 LAST COMMENT_BODY TRUE
J 0
(-8425 5475);
DISPLAY 0.872340 (-8425 5475);
PAINT GREEN (-8425 5475);
DISPLAY INVISIBLE (-8425 5475);
FORCEPROP 1 LAST OFFPAGE TRUE
J 0
(-8225 5450);
DISPLAY 0.872340 (-8225 5450);
PAINT GREEN (-8225 5450);
DISPLAY INVISIBLE (-8225 5450);
FORCEPROP 2 LAST CDS_LIB mstr_standard
J 0
(-8550 5575);
DISPLAY 0.723404 (-8550 5575);
PAINT MONO (-8550 5575);
DISPLAY INVISIBLE (-8550 5575);
FORCEADD TAP..1
R 2
(-7950 5125);
FORCEPROP 3 LASTPIN (-7900 5125) SIG_NAME M_B_CPU0_SB_CA<6>
J 0
(-7890 5135);
DISPLAY 0.659574 (-7890 5135);
PAINT MONO (-7890 5135);
DISPLAY INVISIBLE (-7890 5135);
FORCEPROP 1 LASTPIN (-7900 5125) BN 6
J 2
(-7888 5133);
DISPLAY 0.489362 (-7888 5133);
PAINT GREEN (-7888 5133);
FORCEPROP 2 LAST CDS_LIB mstr_standard
J 0
(-7950 5125);
DISPLAY 0.723404 (-7950 5125);
PAINT MONO (-7950 5125);
DISPLAY INVISIBLE (-7950 5125);
FORCEPROP 1 LAST BODY_TYPE PLUMBING
J 2
(-7950 5175);
DISPLAY 0.872340 (-7950 5175);
PAINT GREEN (-7950 5175);
DISPLAY INVISIBLE (-7950 5175);
FORCEPROP 1 LAST HDL_TAP TRUE
J 2
(-8275 5000);
DISPLAY 0.872340 (-8275 5000);
DISPLAY INVISIBLE (-8275 5000);
FORCEPROP 1 LAST PATH I263
J 2
(-7948 5125);
DISPLAY 0.872340 (-7948 5125);
PAINT GREEN (-7948 5125);
DISPLAY INVISIBLE (-7948 5125);
FORCEADD TAP..1
R 2
(-7950 5025);
FORCEPROP 3 LASTPIN (-7900 5025) SIG_NAME M_B_CPU0_SB_CA<4>
J 0
(-7890 5035);
DISPLAY 0.659574 (-7890 5035);
PAINT MONO (-7890 5035);
DISPLAY INVISIBLE (-7890 5035);
FORCEPROP 1 LASTPIN (-7900 5025) BN 4
J 2
(-7888 5033);
DISPLAY 0.489362 (-7888 5033);
PAINT GREEN (-7888 5033);
FORCEPROP 2 LAST CDS_LIB mstr_standard
J 0
(-7950 5025);
DISPLAY 0.723404 (-7950 5025);
PAINT MONO (-7950 5025);
DISPLAY INVISIBLE (-7950 5025);
FORCEPROP 1 LAST BODY_TYPE PLUMBING
J 2
(-7950 5075);
DISPLAY 0.872340 (-7950 5075);
PAINT GREEN (-7950 5075);
DISPLAY INVISIBLE (-7950 5075);
FORCEPROP 1 LAST HDL_TAP TRUE
J 2
(-8275 4900);
DISPLAY 0.872340 (-8275 4900);
DISPLAY INVISIBLE (-8275 4900);
FORCEPROP 1 LAST PATH I264
J 2
(-7948 5025);
DISPLAY 0.872340 (-7948 5025);
PAINT GREEN (-7948 5025);
DISPLAY INVISIBLE (-7948 5025);
FORCEADD TAP..1
R 2
(-7950 5075);
FORCEPROP 3 LASTPIN (-7900 5075) SIG_NAME M_B_CPU0_SB_CA<5>
J 0
(-7890 5085);
DISPLAY 0.659574 (-7890 5085);
PAINT MONO (-7890 5085);
DISPLAY INVISIBLE (-7890 5085);
FORCEPROP 1 LASTPIN (-7900 5075) BN 5
J 2
(-7888 5083);
DISPLAY 0.489362 (-7888 5083);
PAINT GREEN (-7888 5083);
FORCEPROP 2 LAST CDS_LIB mstr_standard
J 0
(-7950 5075);
DISPLAY 0.723404 (-7950 5075);
PAINT MONO (-7950 5075);
DISPLAY INVISIBLE (-7950 5075);
FORCEPROP 1 LAST BODY_TYPE PLUMBING
J 2
(-7950 5125);
DISPLAY 0.872340 (-7950 5125);
PAINT GREEN (-7950 5125);
DISPLAY INVISIBLE (-7950 5125);
FORCEPROP 1 LAST HDL_TAP TRUE
J 2
(-8275 4950);
DISPLAY 0.872340 (-8275 4950);
DISPLAY INVISIBLE (-8275 4950);
FORCEPROP 1 LAST PATH I265
J 2
(-7948 5075);
DISPLAY 0.872340 (-7948 5075);
PAINT GREEN (-7948 5075);
DISPLAY INVISIBLE (-7948 5075);
FORCEADD TAP..1
R 2
(-7950 5225);
FORCEPROP 3 LASTPIN (-7900 5225) SIG_NAME M_B_CPU0_SA_CA<0>
J 0
(-7890 5235);
DISPLAY 0.659574 (-7890 5235);
PAINT MONO (-7890 5235);
DISPLAY INVISIBLE (-7890 5235);
FORCEPROP 1 LASTPIN (-7900 5225) BN 0
J 2
(-7888 5233);
DISPLAY 0.489362 (-7888 5233);
PAINT GREEN (-7888 5233);
FORCEPROP 2 LAST CDS_LIB mstr_standard
J 0
(-7950 5225);
DISPLAY 0.723404 (-7950 5225);
PAINT MONO (-7950 5225);
DISPLAY INVISIBLE (-7950 5225);
FORCEPROP 1 LAST BODY_TYPE PLUMBING
J 2
(-7950 5275);
DISPLAY 0.872340 (-7950 5275);
PAINT GREEN (-7950 5275);
DISPLAY INVISIBLE (-7950 5275);
FORCEPROP 1 LAST HDL_TAP TRUE
J 2
(-8275 5100);
DISPLAY 0.872340 (-8275 5100);
DISPLAY INVISIBLE (-8275 5100);
FORCEPROP 1 LAST PATH I266
J 2
(-7948 5225);
DISPLAY 0.872340 (-7948 5225);
PAINT GREEN (-7948 5225);
DISPLAY INVISIBLE (-7948 5225);
FORCEADD TAP..1
R 2
(-7950 5275);
FORCEPROP 3 LASTPIN (-7900 5275) SIG_NAME M_B_CPU0_SA_CA<1>
J 0
(-7890 5285);
DISPLAY 0.659574 (-7890 5285);
PAINT MONO (-7890 5285);
DISPLAY INVISIBLE (-7890 5285);
FORCEPROP 1 LASTPIN (-7900 5275) BN 1
J 2
(-7888 5283);
DISPLAY 0.489362 (-7888 5283);
PAINT GREEN (-7888 5283);
FORCEPROP 2 LAST CDS_LIB mstr_standard
J 0
(-7950 5275);
DISPLAY 0.723404 (-7950 5275);
PAINT MONO (-7950 5275);
DISPLAY INVISIBLE (-7950 5275);
FORCEPROP 1 LAST BODY_TYPE PLUMBING
J 2
(-7950 5325);
DISPLAY 0.872340 (-7950 5325);
PAINT GREEN (-7950 5325);
DISPLAY INVISIBLE (-7950 5325);
FORCEPROP 1 LAST HDL_TAP TRUE
J 2
(-8275 5150);
DISPLAY 0.872340 (-8275 5150);
DISPLAY INVISIBLE (-8275 5150);
FORCEPROP 1 LAST PATH I267
J 2
(-7948 5275);
DISPLAY 0.872340 (-7948 5275);
PAINT GREEN (-7948 5275);
DISPLAY INVISIBLE (-7948 5275);
FORCEADD TAP..1
R 2
(-7950 5325);
FORCEPROP 3 LASTPIN (-7900 5325) SIG_NAME M_B_CPU0_SA_CA<2>
J 0
(-7890 5335);
DISPLAY 0.659574 (-7890 5335);
PAINT MONO (-7890 5335);
DISPLAY INVISIBLE (-7890 5335);
FORCEPROP 1 LASTPIN (-7900 5325) BN 2
J 2
(-7888 5333);
DISPLAY 0.489362 (-7888 5333);
PAINT GREEN (-7888 5333);
FORCEPROP 2 LAST CDS_LIB mstr_standard
J 0
(-7950 5325);
DISPLAY 0.723404 (-7950 5325);
PAINT MONO (-7950 5325);
DISPLAY INVISIBLE (-7950 5325);
FORCEPROP 1 LAST BODY_TYPE PLUMBING
J 2
(-7950 5375);
DISPLAY 0.872340 (-7950 5375);
PAINT GREEN (-7950 5375);
DISPLAY INVISIBLE (-7950 5375);
FORCEPROP 1 LAST HDL_TAP TRUE
J 2
(-8275 5200);
DISPLAY 0.872340 (-8275 5200);
DISPLAY INVISIBLE (-8275 5200);
FORCEPROP 1 LAST PATH I268
J 2
(-7948 5325);
DISPLAY 0.872340 (-7948 5325);
PAINT GREEN (-7948 5325);
DISPLAY INVISIBLE (-7948 5325);
FORCEADD TAP..1
R 2
(-7950 5375);
FORCEPROP 3 LASTPIN (-7900 5375) SIG_NAME M_B_CPU0_SA_CA<3>
J 0
(-7890 5385);
DISPLAY 0.659574 (-7890 5385);
PAINT MONO (-7890 5385);
DISPLAY INVISIBLE (-7890 5385);
FORCEPROP 1 LASTPIN (-7900 5375) BN 3
J 2
(-7888 5383);
DISPLAY 0.489362 (-7888 5383);
PAINT GREEN (-7888 5383);
FORCEPROP 2 LAST CDS_LIB mstr_standard
J 0
(-7950 5375);
DISPLAY 0.723404 (-7950 5375);
PAINT MONO (-7950 5375);
DISPLAY INVISIBLE (-7950 5375);
FORCEPROP 1 LAST BODY_TYPE PLUMBING
J 2
(-7950 5425);
DISPLAY 0.872340 (-7950 5425);
PAINT GREEN (-7950 5425);
DISPLAY INVISIBLE (-7950 5425);
FORCEPROP 1 LAST HDL_TAP TRUE
J 2
(-8275 5250);
DISPLAY 0.872340 (-8275 5250);
DISPLAY INVISIBLE (-8275 5250);
FORCEPROP 1 LAST PATH I269
J 2
(-7948 5375);
DISPLAY 0.872340 (-7948 5375);
PAINT GREEN (-7948 5375);
DISPLAY INVISIBLE (-7948 5375);
FORCEADD TAP..1
R 2
(-7950 5475);
FORCEPROP 3 LASTPIN (-7900 5475) SIG_NAME M_B_CPU0_SA_CA<5>
J 0
(-7890 5485);
DISPLAY 0.659574 (-7890 5485);
PAINT MONO (-7890 5485);
DISPLAY INVISIBLE (-7890 5485);
FORCEPROP 1 LASTPIN (-7900 5475) BN 5
J 2
(-7888 5483);
DISPLAY 0.489362 (-7888 5483);
PAINT GREEN (-7888 5483);
FORCEPROP 2 LAST CDS_LIB mstr_standard
J 0
(-7950 5475);
DISPLAY 0.723404 (-7950 5475);
PAINT MONO (-7950 5475);
DISPLAY INVISIBLE (-7950 5475);
FORCEPROP 1 LAST BODY_TYPE PLUMBING
J 2
(-7950 5525);
DISPLAY 0.872340 (-7950 5525);
PAINT GREEN (-7950 5525);
DISPLAY INVISIBLE (-7950 5525);
FORCEPROP 1 LAST HDL_TAP TRUE
J 2
(-8275 5350);
DISPLAY 0.872340 (-8275 5350);
DISPLAY INVISIBLE (-8275 5350);
FORCEPROP 1 LAST PATH I270
J 2
(-7948 5475);
DISPLAY 0.872340 (-7948 5475);
PAINT GREEN (-7948 5475);
DISPLAY INVISIBLE (-7948 5475);
FORCEADD TAP..1
R 2
(-7950 5425);
FORCEPROP 3 LASTPIN (-7900 5425) SIG_NAME M_B_CPU0_SA_CA<4>
J 0
(-7890 5435);
DISPLAY 0.659574 (-7890 5435);
PAINT MONO (-7890 5435);
DISPLAY INVISIBLE (-7890 5435);
FORCEPROP 1 LASTPIN (-7900 5425) BN 4
J 2
(-7888 5433);
DISPLAY 0.489362 (-7888 5433);
PAINT GREEN (-7888 5433);
FORCEPROP 2 LAST CDS_LIB mstr_standard
J 0
(-7950 5425);
DISPLAY 0.723404 (-7950 5425);
PAINT MONO (-7950 5425);
DISPLAY INVISIBLE (-7950 5425);
FORCEPROP 1 LAST BODY_TYPE PLUMBING
J 2
(-7950 5475);
DISPLAY 0.872340 (-7950 5475);
PAINT GREEN (-7950 5475);
DISPLAY INVISIBLE (-7950 5475);
FORCEPROP 1 LAST HDL_TAP TRUE
J 2
(-8275 5300);
DISPLAY 0.872340 (-8275 5300);
DISPLAY INVISIBLE (-8275 5300);
FORCEPROP 1 LAST PATH I271
J 2
(-7948 5425);
DISPLAY 0.872340 (-7948 5425);
PAINT GREEN (-7948 5425);
DISPLAY INVISIBLE (-7948 5425);
FORCEADD TAP..1
R 2
(-7950 5525);
FORCEPROP 3 LASTPIN (-7900 5525) SIG_NAME M_B_CPU0_SA_CA<6>
J 0
(-7890 5535);
DISPLAY 0.659574 (-7890 5535);
PAINT MONO (-7890 5535);
DISPLAY INVISIBLE (-7890 5535);
FORCEPROP 1 LASTPIN (-7900 5525) BN 6
J 2
(-7888 5533);
DISPLAY 0.489362 (-7888 5533);
PAINT GREEN (-7888 5533);
FORCEPROP 2 LAST CDS_LIB mstr_standard
J 0
(-7950 5525);
DISPLAY 0.723404 (-7950 5525);
PAINT MONO (-7950 5525);
DISPLAY INVISIBLE (-7950 5525);
FORCEPROP 1 LAST BODY_TYPE PLUMBING
J 2
(-7950 5575);
DISPLAY 0.872340 (-7950 5575);
PAINT GREEN (-7950 5575);
DISPLAY INVISIBLE (-7950 5575);
FORCEPROP 1 LAST HDL_TAP TRUE
J 2
(-8275 5400);
DISPLAY 0.872340 (-8275 5400);
DISPLAY INVISIBLE (-8275 5400);
FORCEPROP 1 LAST PATH I272
J 2
(-7948 5525);
DISPLAY 0.872340 (-7948 5525);
PAINT GREEN (-7948 5525);
DISPLAY INVISIBLE (-7948 5525);
FORCEADD TAP..1
(-6250 5125);
FORCEPROP 3 LASTPIN (-6300 5125) SIG_NAME M_B_CPU0_SA_DQ<23>
J 0
(-6290 5135);
DISPLAY 0.659574 (-6290 5135);
PAINT MONO (-6290 5135);
DISPLAY INVISIBLE (-6290 5135);
FORCEPROP 1 LASTPIN (-6300 5125) BN 23
J 0
(-6312 5133);
DISPLAY 0.489362 (-6312 5133);
PAINT GREEN (-6312 5133);
FORCEPROP 2 LAST CDS_LIB mstr_standard
J 0
(-6250 5125);
DISPLAY 0.723404 (-6250 5125);
PAINT MONO (-6250 5125);
DISPLAY INVISIBLE (-6250 5125);
FORCEPROP 1 LAST BODY_TYPE PLUMBING
J 0
(-6250 5175);
DISPLAY 0.872340 (-6250 5175);
PAINT GREEN (-6250 5175);
DISPLAY INVISIBLE (-6250 5175);
FORCEPROP 1 LAST HDL_TAP TRUE
J 0
(-5925 5000);
DISPLAY 0.872340 (-5925 5000);
DISPLAY INVISIBLE (-5925 5000);
FORCEPROP 1 LAST PATH I273
J 0
(-6252 5125);
DISPLAY 0.872340 (-6252 5125);
PAINT GREEN (-6252 5125);
DISPLAY INVISIBLE (-6252 5125);
FORCEADD TAP..1
(-6250 5025);
FORCEPROP 3 LASTPIN (-6300 5025) SIG_NAME M_B_CPU0_SA_DQ<21>
J 0
(-6290 5035);
DISPLAY 0.659574 (-6290 5035);
PAINT MONO (-6290 5035);
DISPLAY INVISIBLE (-6290 5035);
FORCEPROP 1 LASTPIN (-6300 5025) BN 21
J 0
(-6312 5033);
DISPLAY 0.489362 (-6312 5033);
PAINT GREEN (-6312 5033);
FORCEPROP 2 LAST CDS_LIB mstr_standard
J 0
(-6250 5025);
DISPLAY 0.723404 (-6250 5025);
PAINT MONO (-6250 5025);
DISPLAY INVISIBLE (-6250 5025);
FORCEPROP 1 LAST BODY_TYPE PLUMBING
J 0
(-6250 5075);
DISPLAY 0.872340 (-6250 5075);
PAINT GREEN (-6250 5075);
DISPLAY INVISIBLE (-6250 5075);
FORCEPROP 1 LAST HDL_TAP TRUE
J 0
(-5925 4900);
DISPLAY 0.872340 (-5925 4900);
DISPLAY INVISIBLE (-5925 4900);
FORCEPROP 1 LAST PATH I274
J 0
(-6252 5025);
DISPLAY 0.872340 (-6252 5025);
PAINT GREEN (-6252 5025);
DISPLAY INVISIBLE (-6252 5025);
FORCEADD TAP..1
(-6250 5075);
FORCEPROP 3 LASTPIN (-6300 5075) SIG_NAME M_B_CPU0_SA_DQ<22>
J 0
(-6290 5085);
DISPLAY 0.659574 (-6290 5085);
PAINT MONO (-6290 5085);
DISPLAY INVISIBLE (-6290 5085);
FORCEPROP 1 LASTPIN (-6300 5075) BN 22
J 0
(-6312 5083);
DISPLAY 0.489362 (-6312 5083);
PAINT GREEN (-6312 5083);
FORCEPROP 2 LAST CDS_LIB mstr_standard
J 0
(-6250 5075);
DISPLAY 0.723404 (-6250 5075);
PAINT MONO (-6250 5075);
DISPLAY INVISIBLE (-6250 5075);
FORCEPROP 1 LAST BODY_TYPE PLUMBING
J 0
(-6250 5125);
DISPLAY 0.872340 (-6250 5125);
PAINT GREEN (-6250 5125);
DISPLAY INVISIBLE (-6250 5125);
FORCEPROP 1 LAST HDL_TAP TRUE
J 0
(-5925 4950);
DISPLAY 0.872340 (-5925 4950);
DISPLAY INVISIBLE (-5925 4950);
FORCEPROP 1 LAST PATH I275
J 0
(-6252 5075);
DISPLAY 0.872340 (-6252 5075);
PAINT GREEN (-6252 5075);
DISPLAY INVISIBLE (-6252 5075);
FORCEADD TAP..1
(-6250 5175);
FORCEPROP 3 LASTPIN (-6300 5175) SIG_NAME M_B_CPU0_SA_DQ<24>
J 0
(-6290 5185);
DISPLAY 0.659574 (-6290 5185);
PAINT MONO (-6290 5185);
DISPLAY INVISIBLE (-6290 5185);
FORCEPROP 1 LASTPIN (-6300 5175) BN 24
J 0
(-6312 5183);
DISPLAY 0.489362 (-6312 5183);
PAINT GREEN (-6312 5183);
FORCEPROP 2 LAST CDS_LIB mstr_standard
J 0
(-6250 5175);
DISPLAY 0.723404 (-6250 5175);
PAINT MONO (-6250 5175);
DISPLAY INVISIBLE (-6250 5175);
FORCEPROP 1 LAST BODY_TYPE PLUMBING
J 0
(-6250 5225);
DISPLAY 0.872340 (-6250 5225);
PAINT GREEN (-6250 5225);
DISPLAY INVISIBLE (-6250 5225);
FORCEPROP 1 LAST HDL_TAP TRUE
J 0
(-5925 5050);
DISPLAY 0.872340 (-5925 5050);
DISPLAY INVISIBLE (-5925 5050);
FORCEPROP 1 LAST PATH I276
J 0
(-6252 5175);
DISPLAY 0.872340 (-6252 5175);
PAINT GREEN (-6252 5175);
DISPLAY INVISIBLE (-6252 5175);
FORCEADD TAP..1
(-6250 5225);
FORCEPROP 3 LASTPIN (-6300 5225) SIG_NAME M_B_CPU0_SA_DQ<25>
J 0
(-6290 5235);
DISPLAY 0.659574 (-6290 5235);
PAINT MONO (-6290 5235);
DISPLAY INVISIBLE (-6290 5235);
FORCEPROP 1 LASTPIN (-6300 5225) BN 25
J 0
(-6312 5233);
DISPLAY 0.489362 (-6312 5233);
PAINT GREEN (-6312 5233);
FORCEPROP 2 LAST CDS_LIB mstr_standard
J 0
(-6250 5225);
DISPLAY 0.723404 (-6250 5225);
PAINT MONO (-6250 5225);
DISPLAY INVISIBLE (-6250 5225);
FORCEPROP 1 LAST BODY_TYPE PLUMBING
J 0
(-6250 5275);
DISPLAY 0.872340 (-6250 5275);
PAINT GREEN (-6250 5275);
DISPLAY INVISIBLE (-6250 5275);
FORCEPROP 1 LAST HDL_TAP TRUE
J 0
(-5925 5100);
DISPLAY 0.872340 (-5925 5100);
DISPLAY INVISIBLE (-5925 5100);
FORCEPROP 1 LAST PATH I277
J 0
(-6252 5225);
DISPLAY 0.872340 (-6252 5225);
PAINT GREEN (-6252 5225);
DISPLAY INVISIBLE (-6252 5225);
FORCEADD TAP..1
(-6250 5275);
FORCEPROP 3 LASTPIN (-6300 5275) SIG_NAME M_B_CPU0_SA_DQ<26>
J 0
(-6290 5285);
DISPLAY 0.659574 (-6290 5285);
PAINT MONO (-6290 5285);
DISPLAY INVISIBLE (-6290 5285);
FORCEPROP 1 LASTPIN (-6300 5275) BN 26
J 0
(-6312 5283);
DISPLAY 0.489362 (-6312 5283);
PAINT GREEN (-6312 5283);
FORCEPROP 2 LAST CDS_LIB mstr_standard
J 0
(-6250 5275);
DISPLAY 0.723404 (-6250 5275);
PAINT MONO (-6250 5275);
DISPLAY INVISIBLE (-6250 5275);
FORCEPROP 1 LAST BODY_TYPE PLUMBING
J 0
(-6250 5325);
DISPLAY 0.872340 (-6250 5325);
PAINT GREEN (-6250 5325);
DISPLAY INVISIBLE (-6250 5325);
FORCEPROP 1 LAST HDL_TAP TRUE
J 0
(-5925 5150);
DISPLAY 0.872340 (-5925 5150);
DISPLAY INVISIBLE (-5925 5150);
FORCEPROP 1 LAST PATH I278
J 0
(-6252 5275);
DISPLAY 0.872340 (-6252 5275);
PAINT GREEN (-6252 5275);
DISPLAY INVISIBLE (-6252 5275);
FORCEADD TAP..1
(-6250 5525);
FORCEPROP 3 LASTPIN (-6300 5525) SIG_NAME M_B_CPU0_SA_DQ<31>
J 0
(-6290 5535);
DISPLAY 0.659574 (-6290 5535);
PAINT MONO (-6290 5535);
DISPLAY INVISIBLE (-6290 5535);
FORCEPROP 1 LASTPIN (-6300 5525) BN 31
J 0
(-6312 5533);
DISPLAY 0.489362 (-6312 5533);
PAINT GREEN (-6312 5533);
FORCEPROP 2 LAST CDS_LIB mstr_standard
J 0
(-6250 5525);
DISPLAY 0.723404 (-6250 5525);
PAINT MONO (-6250 5525);
DISPLAY INVISIBLE (-6250 5525);
FORCEPROP 1 LAST BODY_TYPE PLUMBING
J 0
(-6250 5575);
DISPLAY 0.872340 (-6250 5575);
PAINT GREEN (-6250 5575);
DISPLAY INVISIBLE (-6250 5575);
FORCEPROP 1 LAST HDL_TAP TRUE
J 0
(-5925 5400);
DISPLAY 0.872340 (-5925 5400);
DISPLAY INVISIBLE (-5925 5400);
FORCEPROP 1 LAST PATH I279
J 0
(-6252 5525);
DISPLAY 0.872340 (-6252 5525);
PAINT GREEN (-6252 5525);
DISPLAY INVISIBLE (-6252 5525);
FORCEADD TAP..1
(-6250 5325);
FORCEPROP 3 LASTPIN (-6300 5325) SIG_NAME M_B_CPU0_SA_DQ<27>
J 0
(-6290 5335);
DISPLAY 0.659574 (-6290 5335);
PAINT MONO (-6290 5335);
DISPLAY INVISIBLE (-6290 5335);
FORCEPROP 1 LASTPIN (-6300 5325) BN 27
J 0
(-6312 5333);
DISPLAY 0.489362 (-6312 5333);
PAINT GREEN (-6312 5333);
FORCEPROP 2 LAST CDS_LIB mstr_standard
J 0
(-6250 5325);
DISPLAY 0.723404 (-6250 5325);
PAINT MONO (-6250 5325);
DISPLAY INVISIBLE (-6250 5325);
FORCEPROP 1 LAST BODY_TYPE PLUMBING
J 0
(-6250 5375);
DISPLAY 0.872340 (-6250 5375);
PAINT GREEN (-6250 5375);
DISPLAY INVISIBLE (-6250 5375);
FORCEPROP 1 LAST HDL_TAP TRUE
J 0
(-5925 5200);
DISPLAY 0.872340 (-5925 5200);
DISPLAY INVISIBLE (-5925 5200);
FORCEPROP 1 LAST PATH I280
J 0
(-6252 5325);
DISPLAY 0.872340 (-6252 5325);
PAINT GREEN (-6252 5325);
DISPLAY INVISIBLE (-6252 5325);
FORCEADD TAP..1
(-6250 5375);
FORCEPROP 3 LASTPIN (-6300 5375) SIG_NAME M_B_CPU0_SA_DQ<28>
J 0
(-6290 5385);
DISPLAY 0.659574 (-6290 5385);
PAINT MONO (-6290 5385);
DISPLAY INVISIBLE (-6290 5385);
FORCEPROP 1 LASTPIN (-6300 5375) BN 28
J 0
(-6312 5383);
DISPLAY 0.489362 (-6312 5383);
PAINT GREEN (-6312 5383);
FORCEPROP 2 LAST CDS_LIB mstr_standard
J 0
(-6250 5375);
DISPLAY 0.723404 (-6250 5375);
PAINT MONO (-6250 5375);
DISPLAY INVISIBLE (-6250 5375);
FORCEPROP 1 LAST BODY_TYPE PLUMBING
J 0
(-6250 5425);
DISPLAY 0.872340 (-6250 5425);
PAINT GREEN (-6250 5425);
DISPLAY INVISIBLE (-6250 5425);
FORCEPROP 1 LAST HDL_TAP TRUE
J 0
(-5925 5250);
DISPLAY 0.872340 (-5925 5250);
DISPLAY INVISIBLE (-5925 5250);
FORCEPROP 1 LAST PATH I281
J 0
(-6252 5375);
DISPLAY 0.872340 (-6252 5375);
PAINT GREEN (-6252 5375);
DISPLAY INVISIBLE (-6252 5375);
FORCEADD TAP..1
(-6250 5475);
FORCEPROP 3 LASTPIN (-6300 5475) SIG_NAME M_B_CPU0_SA_DQ<30>
J 0
(-6290 5485);
DISPLAY 0.659574 (-6290 5485);
PAINT MONO (-6290 5485);
DISPLAY INVISIBLE (-6290 5485);
FORCEPROP 1 LASTPIN (-6300 5475) BN 30
J 0
(-6312 5483);
DISPLAY 0.489362 (-6312 5483);
PAINT GREEN (-6312 5483);
FORCEPROP 2 LAST CDS_LIB mstr_standard
J 0
(-6250 5475);
DISPLAY 0.723404 (-6250 5475);
PAINT MONO (-6250 5475);
DISPLAY INVISIBLE (-6250 5475);
FORCEPROP 1 LAST BODY_TYPE PLUMBING
J 0
(-6250 5525);
DISPLAY 0.872340 (-6250 5525);
PAINT GREEN (-6250 5525);
DISPLAY INVISIBLE (-6250 5525);
FORCEPROP 1 LAST HDL_TAP TRUE
J 0
(-5925 5350);
DISPLAY 0.872340 (-5925 5350);
DISPLAY INVISIBLE (-5925 5350);
FORCEPROP 1 LAST PATH I282
J 0
(-6252 5475);
DISPLAY 0.872340 (-6252 5475);
PAINT GREEN (-6252 5475);
DISPLAY INVISIBLE (-6252 5475);
FORCEADD TAP..1
(-6250 5425);
FORCEPROP 3 LASTPIN (-6300 5425) SIG_NAME M_B_CPU0_SA_DQ<29>
J 0
(-6290 5435);
DISPLAY 0.659574 (-6290 5435);
PAINT MONO (-6290 5435);
DISPLAY INVISIBLE (-6290 5435);
FORCEPROP 1 LASTPIN (-6300 5425) BN 29
J 0
(-6312 5433);
DISPLAY 0.489362 (-6312 5433);
PAINT GREEN (-6312 5433);
FORCEPROP 2 LAST CDS_LIB mstr_standard
J 0
(-6250 5425);
DISPLAY 0.723404 (-6250 5425);
PAINT MONO (-6250 5425);
DISPLAY INVISIBLE (-6250 5425);
FORCEPROP 1 LAST BODY_TYPE PLUMBING
J 0
(-6250 5475);
DISPLAY 0.872340 (-6250 5475);
PAINT GREEN (-6250 5475);
DISPLAY INVISIBLE (-6250 5475);
FORCEPROP 1 LAST HDL_TAP TRUE
J 0
(-5925 5300);
DISPLAY 0.872340 (-5925 5300);
DISPLAY INVISIBLE (-5925 5300);
FORCEPROP 1 LAST PATH I283
J 0
(-6252 5425);
DISPLAY 0.872340 (-6252 5425);
PAINT GREEN (-6252 5425);
DISPLAY INVISIBLE (-6252 5425);
FORCEADD OFFPAGE..3
(-5500 5575);
FORCEPROP 2 LAST $XR0 11 
J 0
(-5286 5575);
DISPLAY 0.638298 (-5286 5575);
PAINT MONO (-5286 5575);
FORCEPROP 2 LAST PATH I284
J 0
(-5275 5625);
DISPLAY 0.808511 (-5275 5625);
DISPLAY INVISIBLE (-5275 5625);
FORCEPROP 1 LAST COMMENT_BODY TRUE
J 0
(-5550 5475);
DISPLAY 0.872340 (-5550 5475);
PAINT GREEN (-5550 5475);
DISPLAY INVISIBLE (-5550 5475);
FORCEPROP 1 LAST OFFPAGE TRUE
J 0
(-5175 5450);
DISPLAY 0.872340 (-5175 5450);
PAINT GREEN (-5175 5450);
DISPLAY INVISIBLE (-5175 5450);
FORCEPROP 2 LAST CDS_LIB mstr_standard
J 0
(-5500 5575);
DISPLAY 0.723404 (-5500 5575);
PAINT MONO (-5500 5575);
DISPLAY INVISIBLE (-5500 5575);
FORCEADD TAP..1
(-3650 2700);
FORCEPROP 3 LASTPIN (-3700 2700) SIG_NAME M_B_CPU0_SB_DQS_DP<0>
J 0
(-3690 2710);
DISPLAY 0.659574 (-3690 2710);
PAINT MONO (-3690 2710);
DISPLAY INVISIBLE (-3690 2710);
FORCEPROP 1 LASTPIN (-3700 2700) BN 0
J 0
(-3712 2708);
DISPLAY 0.489362 (-3712 2708);
PAINT GREEN (-3712 2708);
FORCEPROP 2 LAST CDS_LIB mstr_standard
J 0
(-3650 2700);
DISPLAY 0.723404 (-3650 2700);
PAINT MONO (-3650 2700);
DISPLAY INVISIBLE (-3650 2700);
FORCEPROP 1 LAST BODY_TYPE PLUMBING
J 0
(-3650 2750);
DISPLAY 0.872340 (-3650 2750);
PAINT GREEN (-3650 2750);
DISPLAY INVISIBLE (-3650 2750);
FORCEPROP 1 LAST HDL_TAP TRUE
J 0
(-3325 2575);
DISPLAY 0.872340 (-3325 2575);
DISPLAY INVISIBLE (-3325 2575);
FORCEPROP 1 LAST PATH I285
J 0
(-3652 2700);
DISPLAY 0.872340 (-3652 2700);
PAINT GREEN (-3652 2700);
DISPLAY INVISIBLE (-3652 2700);
FORCEADD TAP..1
(-3650 2800);
FORCEPROP 3 LASTPIN (-3700 2800) SIG_NAME M_B_CPU0_SB_DQS_DP<1>
J 0
(-3690 2810);
DISPLAY 0.659574 (-3690 2810);
PAINT MONO (-3690 2810);
DISPLAY INVISIBLE (-3690 2810);
FORCEPROP 1 LASTPIN (-3700 2800) BN 1
J 0
(-3712 2808);
DISPLAY 0.489362 (-3712 2808);
PAINT GREEN (-3712 2808);
FORCEPROP 2 LAST CDS_LIB mstr_standard
J 0
(-3650 2800);
DISPLAY 0.723404 (-3650 2800);
PAINT MONO (-3650 2800);
DISPLAY INVISIBLE (-3650 2800);
FORCEPROP 1 LAST BODY_TYPE PLUMBING
J 0
(-3650 2850);
DISPLAY 0.872340 (-3650 2850);
PAINT GREEN (-3650 2850);
DISPLAY INVISIBLE (-3650 2850);
FORCEPROP 1 LAST HDL_TAP TRUE
J 0
(-3325 2675);
DISPLAY 0.872340 (-3325 2675);
DISPLAY INVISIBLE (-3325 2675);
FORCEPROP 1 LAST PATH I286
J 0
(-3652 2800);
DISPLAY 0.872340 (-3652 2800);
PAINT GREEN (-3652 2800);
DISPLAY INVISIBLE (-3652 2800);
FORCEADD TAP..1
(-3450 2850);
FORCEPROP 3 LASTPIN (-3500 2850) SIG_NAME M_B_CPU0_SB_DQS_DN<2>
J 0
(-3490 2860);
DISPLAY 0.659574 (-3490 2860);
PAINT MONO (-3490 2860);
DISPLAY INVISIBLE (-3490 2860);
FORCEPROP 1 LASTPIN (-3500 2850) BN 2
J 0
(-3512 2858);
DISPLAY 0.489362 (-3512 2858);
PAINT GREEN (-3512 2858);
FORCEPROP 2 LAST CDS_LIB mstr_standard
J 0
(-3450 2850);
DISPLAY 0.723404 (-3450 2850);
PAINT MONO (-3450 2850);
DISPLAY INVISIBLE (-3450 2850);
FORCEPROP 1 LAST BODY_TYPE PLUMBING
J 0
(-3450 2900);
DISPLAY 0.872340 (-3450 2900);
PAINT GREEN (-3450 2900);
DISPLAY INVISIBLE (-3450 2900);
FORCEPROP 1 LAST HDL_TAP TRUE
J 0
(-3125 2725);
DISPLAY 0.872340 (-3125 2725);
DISPLAY INVISIBLE (-3125 2725);
FORCEPROP 1 LAST PATH I287
J 0
(-3452 2850);
DISPLAY 0.872340 (-3452 2850);
PAINT GREEN (-3452 2850);
DISPLAY INVISIBLE (-3452 2850);
FORCEADD TAP..1
(-3450 2750);
FORCEPROP 3 LASTPIN (-3500 2750) SIG_NAME M_B_CPU0_SB_DQS_DN<1>
J 0
(-3490 2760);
DISPLAY 0.659574 (-3490 2760);
PAINT MONO (-3490 2760);
DISPLAY INVISIBLE (-3490 2760);
FORCEPROP 1 LASTPIN (-3500 2750) BN 1
J 0
(-3512 2758);
DISPLAY 0.489362 (-3512 2758);
PAINT GREEN (-3512 2758);
FORCEPROP 2 LAST CDS_LIB mstr_standard
J 0
(-3450 2750);
DISPLAY 0.723404 (-3450 2750);
PAINT MONO (-3450 2750);
DISPLAY INVISIBLE (-3450 2750);
FORCEPROP 1 LAST BODY_TYPE PLUMBING
J 0
(-3450 2800);
DISPLAY 0.872340 (-3450 2800);
PAINT GREEN (-3450 2800);
DISPLAY INVISIBLE (-3450 2800);
FORCEPROP 1 LAST HDL_TAP TRUE
J 0
(-3125 2625);
DISPLAY 0.872340 (-3125 2625);
DISPLAY INVISIBLE (-3125 2625);
FORCEPROP 1 LAST PATH I288
J 0
(-3452 2750);
DISPLAY 0.872340 (-3452 2750);
PAINT GREEN (-3452 2750);
DISPLAY INVISIBLE (-3452 2750);
FORCEADD TAP..1
(-3450 2650);
FORCEPROP 3 LASTPIN (-3500 2650) SIG_NAME M_B_CPU0_SB_DQS_DN<0>
J 0
(-3490 2660);
DISPLAY 0.659574 (-3490 2660);
PAINT MONO (-3490 2660);
DISPLAY INVISIBLE (-3490 2660);
FORCEPROP 1 LASTPIN (-3500 2650) BN 0
J 0
(-3512 2658);
DISPLAY 0.489362 (-3512 2658);
PAINT GREEN (-3512 2658);
FORCEPROP 2 LAST CDS_LIB mstr_standard
J 0
(-3450 2650);
DISPLAY 0.723404 (-3450 2650);
PAINT MONO (-3450 2650);
DISPLAY INVISIBLE (-3450 2650);
FORCEPROP 1 LAST BODY_TYPE PLUMBING
J 0
(-3450 2700);
DISPLAY 0.872340 (-3450 2700);
PAINT GREEN (-3450 2700);
DISPLAY INVISIBLE (-3450 2700);
FORCEPROP 1 LAST HDL_TAP TRUE
J 0
(-3125 2525);
DISPLAY 0.872340 (-3125 2525);
DISPLAY INVISIBLE (-3125 2525);
FORCEPROP 1 LAST PATH I289
J 0
(-3452 2650);
DISPLAY 0.872340 (-3452 2650);
PAINT GREEN (-3452 2650);
DISPLAY INVISIBLE (-3452 2650);
FORCEADD TAP..1
(-3650 2900);
FORCEPROP 3 LASTPIN (-3700 2900) SIG_NAME M_B_CPU0_SB_DQS_DP<2>
J 0
(-3690 2910);
DISPLAY 0.659574 (-3690 2910);
PAINT MONO (-3690 2910);
DISPLAY INVISIBLE (-3690 2910);
FORCEPROP 1 LASTPIN (-3700 2900) BN 2
J 0
(-3712 2908);
DISPLAY 0.489362 (-3712 2908);
PAINT GREEN (-3712 2908);
FORCEPROP 2 LAST CDS_LIB mstr_standard
J 0
(-3650 2900);
DISPLAY 0.723404 (-3650 2900);
PAINT MONO (-3650 2900);
DISPLAY INVISIBLE (-3650 2900);
FORCEPROP 1 LAST BODY_TYPE PLUMBING
J 0
(-3650 2950);
DISPLAY 0.872340 (-3650 2950);
PAINT GREEN (-3650 2950);
DISPLAY INVISIBLE (-3650 2950);
FORCEPROP 1 LAST HDL_TAP TRUE
J 0
(-3325 2775);
DISPLAY 0.872340 (-3325 2775);
DISPLAY INVISIBLE (-3325 2775);
FORCEPROP 1 LAST PATH I290
J 0
(-3652 2900);
DISPLAY 0.872340 (-3652 2900);
PAINT GREEN (-3652 2900);
DISPLAY INVISIBLE (-3652 2900);
FORCEADD TAP..1
(-3650 3000);
FORCEPROP 3 LASTPIN (-3700 3000) SIG_NAME M_B_CPU0_SB_DQS_DP<3>
J 0
(-3690 3010);
DISPLAY 0.659574 (-3690 3010);
PAINT MONO (-3690 3010);
DISPLAY INVISIBLE (-3690 3010);
FORCEPROP 1 LASTPIN (-3700 3000) BN 3
J 0
(-3712 3008);
DISPLAY 0.489362 (-3712 3008);
PAINT GREEN (-3712 3008);
FORCEPROP 2 LAST CDS_LIB mstr_standard
J 0
(-3650 3000);
DISPLAY 0.723404 (-3650 3000);
PAINT MONO (-3650 3000);
DISPLAY INVISIBLE (-3650 3000);
FORCEPROP 1 LAST BODY_TYPE PLUMBING
J 0
(-3650 3050);
DISPLAY 0.872340 (-3650 3050);
PAINT GREEN (-3650 3050);
DISPLAY INVISIBLE (-3650 3050);
FORCEPROP 1 LAST HDL_TAP TRUE
J 0
(-3325 2875);
DISPLAY 0.872340 (-3325 2875);
DISPLAY INVISIBLE (-3325 2875);
FORCEPROP 1 LAST PATH I291
J 0
(-3652 3000);
DISPLAY 0.872340 (-3652 3000);
PAINT GREEN (-3652 3000);
DISPLAY INVISIBLE (-3652 3000);
FORCEADD TAP..1
(-3650 3100);
FORCEPROP 3 LASTPIN (-3700 3100) SIG_NAME M_B_CPU0_SB_DQS_DP<4>
J 0
(-3690 3110);
DISPLAY 0.659574 (-3690 3110);
PAINT MONO (-3690 3110);
DISPLAY INVISIBLE (-3690 3110);
FORCEPROP 1 LASTPIN (-3700 3100) BN 4
J 0
(-3712 3108);
DISPLAY 0.489362 (-3712 3108);
PAINT GREEN (-3712 3108);
FORCEPROP 2 LAST CDS_LIB mstr_standard
J 0
(-3650 3100);
DISPLAY 0.723404 (-3650 3100);
PAINT MONO (-3650 3100);
DISPLAY INVISIBLE (-3650 3100);
FORCEPROP 1 LAST BODY_TYPE PLUMBING
J 0
(-3650 3150);
DISPLAY 0.872340 (-3650 3150);
PAINT GREEN (-3650 3150);
DISPLAY INVISIBLE (-3650 3150);
FORCEPROP 1 LAST HDL_TAP TRUE
J 0
(-3325 2975);
DISPLAY 0.872340 (-3325 2975);
DISPLAY INVISIBLE (-3325 2975);
FORCEPROP 1 LAST PATH I292
J 0
(-3652 3100);
DISPLAY 0.872340 (-3652 3100);
PAINT GREEN (-3652 3100);
DISPLAY INVISIBLE (-3652 3100);
FORCEADD TAP..1
(-3450 2950);
FORCEPROP 3 LASTPIN (-3500 2950) SIG_NAME M_B_CPU0_SB_DQS_DN<3>
J 0
(-3490 2960);
DISPLAY 0.659574 (-3490 2960);
PAINT MONO (-3490 2960);
DISPLAY INVISIBLE (-3490 2960);
FORCEPROP 1 LASTPIN (-3500 2950) BN 3
J 0
(-3512 2958);
DISPLAY 0.489362 (-3512 2958);
PAINT GREEN (-3512 2958);
FORCEPROP 2 LAST CDS_LIB mstr_standard
J 0
(-3450 2950);
DISPLAY 0.723404 (-3450 2950);
PAINT MONO (-3450 2950);
DISPLAY INVISIBLE (-3450 2950);
FORCEPROP 1 LAST BODY_TYPE PLUMBING
J 0
(-3450 3000);
DISPLAY 0.872340 (-3450 3000);
PAINT GREEN (-3450 3000);
DISPLAY INVISIBLE (-3450 3000);
FORCEPROP 1 LAST HDL_TAP TRUE
J 0
(-3125 2825);
DISPLAY 0.872340 (-3125 2825);
DISPLAY INVISIBLE (-3125 2825);
FORCEPROP 1 LAST PATH I293
J 0
(-3452 2950);
DISPLAY 0.872340 (-3452 2950);
PAINT GREEN (-3452 2950);
DISPLAY INVISIBLE (-3452 2950);
FORCEADD TAP..1
(-3450 3050);
FORCEPROP 3 LASTPIN (-3500 3050) SIG_NAME M_B_CPU0_SB_DQS_DN<4>
J 0
(-3490 3060);
DISPLAY 0.659574 (-3490 3060);
PAINT MONO (-3490 3060);
DISPLAY INVISIBLE (-3490 3060);
FORCEPROP 1 LASTPIN (-3500 3050) BN 4
J 0
(-3512 3058);
DISPLAY 0.489362 (-3512 3058);
PAINT GREEN (-3512 3058);
FORCEPROP 2 LAST CDS_LIB mstr_standard
J 0
(-3450 3050);
DISPLAY 0.723404 (-3450 3050);
PAINT MONO (-3450 3050);
DISPLAY INVISIBLE (-3450 3050);
FORCEPROP 1 LAST BODY_TYPE PLUMBING
J 0
(-3450 3100);
DISPLAY 0.872340 (-3450 3100);
PAINT GREEN (-3450 3100);
DISPLAY INVISIBLE (-3450 3100);
FORCEPROP 1 LAST HDL_TAP TRUE
J 0
(-3125 2925);
DISPLAY 0.872340 (-3125 2925);
DISPLAY INVISIBLE (-3125 2925);
FORCEPROP 1 LAST PATH I294
J 0
(-3452 3050);
DISPLAY 0.872340 (-3452 3050);
PAINT GREEN (-3452 3050);
DISPLAY INVISIBLE (-3452 3050);
FORCEADD TAP..1
(-3650 3200);
FORCEPROP 3 LASTPIN (-3700 3200) SIG_NAME M_B_CPU0_SB_DQS_DP<5>
J 0
(-3690 3210);
DISPLAY 0.659574 (-3690 3210);
PAINT MONO (-3690 3210);
DISPLAY INVISIBLE (-3690 3210);
FORCEPROP 1 LASTPIN (-3700 3200) BN 5
J 0
(-3712 3208);
DISPLAY 0.489362 (-3712 3208);
PAINT GREEN (-3712 3208);
FORCEPROP 2 LAST CDS_LIB mstr_standard
J 0
(-3650 3200);
DISPLAY 0.723404 (-3650 3200);
PAINT MONO (-3650 3200);
DISPLAY INVISIBLE (-3650 3200);
FORCEPROP 1 LAST BODY_TYPE PLUMBING
J 0
(-3650 3250);
DISPLAY 0.872340 (-3650 3250);
PAINT GREEN (-3650 3250);
DISPLAY INVISIBLE (-3650 3250);
FORCEPROP 1 LAST HDL_TAP TRUE
J 0
(-3325 3075);
DISPLAY 0.872340 (-3325 3075);
DISPLAY INVISIBLE (-3325 3075);
FORCEPROP 1 LAST PATH I295
J 0
(-3652 3200);
DISPLAY 0.872340 (-3652 3200);
PAINT GREEN (-3652 3200);
DISPLAY INVISIBLE (-3652 3200);
FORCEADD TAP..1
(-3650 3300);
FORCEPROP 3 LASTPIN (-3700 3300) SIG_NAME M_B_CPU0_SB_DQS_DP<6>
J 0
(-3690 3310);
DISPLAY 0.659574 (-3690 3310);
PAINT MONO (-3690 3310);
DISPLAY INVISIBLE (-3690 3310);
FORCEPROP 1 LASTPIN (-3700 3300) BN 6
J 0
(-3712 3308);
DISPLAY 0.489362 (-3712 3308);
PAINT GREEN (-3712 3308);
FORCEPROP 2 LAST CDS_LIB mstr_standard
J 0
(-3650 3300);
DISPLAY 0.723404 (-3650 3300);
PAINT MONO (-3650 3300);
DISPLAY INVISIBLE (-3650 3300);
FORCEPROP 1 LAST BODY_TYPE PLUMBING
J 0
(-3650 3350);
DISPLAY 0.872340 (-3650 3350);
PAINT GREEN (-3650 3350);
DISPLAY INVISIBLE (-3650 3350);
FORCEPROP 1 LAST HDL_TAP TRUE
J 0
(-3325 3175);
DISPLAY 0.872340 (-3325 3175);
DISPLAY INVISIBLE (-3325 3175);
FORCEPROP 1 LAST PATH I296
J 0
(-3652 3300);
DISPLAY 0.872340 (-3652 3300);
PAINT GREEN (-3652 3300);
DISPLAY INVISIBLE (-3652 3300);
FORCEADD TAP..1
(-3450 3350);
FORCEPROP 3 LASTPIN (-3500 3350) SIG_NAME M_B_CPU0_SB_DQS_DN<7>
J 0
(-3490 3360);
DISPLAY 0.659574 (-3490 3360);
PAINT MONO (-3490 3360);
DISPLAY INVISIBLE (-3490 3360);
FORCEPROP 1 LASTPIN (-3500 3350) BN 7
J 0
(-3512 3358);
DISPLAY 0.489362 (-3512 3358);
PAINT GREEN (-3512 3358);
FORCEPROP 2 LAST CDS_LIB mstr_standard
J 0
(-3450 3350);
DISPLAY 0.723404 (-3450 3350);
PAINT MONO (-3450 3350);
DISPLAY INVISIBLE (-3450 3350);
FORCEPROP 1 LAST BODY_TYPE PLUMBING
J 0
(-3450 3400);
DISPLAY 0.872340 (-3450 3400);
PAINT GREEN (-3450 3400);
DISPLAY INVISIBLE (-3450 3400);
FORCEPROP 1 LAST HDL_TAP TRUE
J 0
(-3125 3225);
DISPLAY 0.872340 (-3125 3225);
DISPLAY INVISIBLE (-3125 3225);
FORCEPROP 1 LAST PATH I297
J 0
(-3452 3350);
DISPLAY 0.872340 (-3452 3350);
PAINT GREEN (-3452 3350);
DISPLAY INVISIBLE (-3452 3350);
FORCEADD TAP..1
(-3450 3250);
FORCEPROP 3 LASTPIN (-3500 3250) SIG_NAME M_B_CPU0_SB_DQS_DN<6>
J 0
(-3490 3260);
DISPLAY 0.659574 (-3490 3260);
PAINT MONO (-3490 3260);
DISPLAY INVISIBLE (-3490 3260);
FORCEPROP 1 LASTPIN (-3500 3250) BN 6
J 0
(-3512 3258);
DISPLAY 0.489362 (-3512 3258);
PAINT GREEN (-3512 3258);
FORCEPROP 2 LAST CDS_LIB mstr_standard
J 0
(-3450 3250);
DISPLAY 0.723404 (-3450 3250);
PAINT MONO (-3450 3250);
DISPLAY INVISIBLE (-3450 3250);
FORCEPROP 1 LAST BODY_TYPE PLUMBING
J 0
(-3450 3300);
DISPLAY 0.872340 (-3450 3300);
PAINT GREEN (-3450 3300);
DISPLAY INVISIBLE (-3450 3300);
FORCEPROP 1 LAST HDL_TAP TRUE
J 0
(-3125 3125);
DISPLAY 0.872340 (-3125 3125);
DISPLAY INVISIBLE (-3125 3125);
FORCEPROP 1 LAST PATH I298
J 0
(-3452 3250);
DISPLAY 0.872340 (-3452 3250);
PAINT GREEN (-3452 3250);
DISPLAY INVISIBLE (-3452 3250);
FORCEADD TAP..1
(-3450 3150);
FORCEPROP 3 LASTPIN (-3500 3150) SIG_NAME M_B_CPU0_SB_DQS_DN<5>
J 0
(-3490 3160);
DISPLAY 0.659574 (-3490 3160);
PAINT MONO (-3490 3160);
DISPLAY INVISIBLE (-3490 3160);
FORCEPROP 1 LASTPIN (-3500 3150) BN 5
J 0
(-3512 3158);
DISPLAY 0.489362 (-3512 3158);
PAINT GREEN (-3512 3158);
FORCEPROP 2 LAST CDS_LIB mstr_standard
J 0
(-3450 3150);
DISPLAY 0.723404 (-3450 3150);
PAINT MONO (-3450 3150);
DISPLAY INVISIBLE (-3450 3150);
FORCEPROP 1 LAST BODY_TYPE PLUMBING
J 0
(-3450 3200);
DISPLAY 0.872340 (-3450 3200);
PAINT GREEN (-3450 3200);
DISPLAY INVISIBLE (-3450 3200);
FORCEPROP 1 LAST HDL_TAP TRUE
J 0
(-3125 3025);
DISPLAY 0.872340 (-3125 3025);
DISPLAY INVISIBLE (-3125 3025);
FORCEPROP 1 LAST PATH I299
J 0
(-3452 3150);
DISPLAY 0.872340 (-3452 3150);
PAINT GREEN (-3452 3150);
DISPLAY INVISIBLE (-3452 3150);
FORCEADD TAP..1
(-3650 3400);
FORCEPROP 3 LASTPIN (-3700 3400) SIG_NAME M_B_CPU0_SB_DQS_DP<7>
J 0
(-3690 3410);
DISPLAY 0.659574 (-3690 3410);
PAINT MONO (-3690 3410);
DISPLAY INVISIBLE (-3690 3410);
FORCEPROP 1 LASTPIN (-3700 3400) BN 7
J 0
(-3712 3408);
DISPLAY 0.489362 (-3712 3408);
PAINT GREEN (-3712 3408);
FORCEPROP 2 LAST CDS_LIB mstr_standard
J 0
(-3650 3400);
DISPLAY 0.723404 (-3650 3400);
PAINT MONO (-3650 3400);
DISPLAY INVISIBLE (-3650 3400);
FORCEPROP 1 LAST BODY_TYPE PLUMBING
J 0
(-3650 3450);
DISPLAY 0.872340 (-3650 3450);
PAINT GREEN (-3650 3450);
DISPLAY INVISIBLE (-3650 3450);
FORCEPROP 1 LAST HDL_TAP TRUE
J 0
(-3325 3275);
DISPLAY 0.872340 (-3325 3275);
DISPLAY INVISIBLE (-3325 3275);
FORCEPROP 1 LAST PATH I300
J 0
(-3652 3400);
DISPLAY 0.872340 (-3652 3400);
PAINT GREEN (-3652 3400);
DISPLAY INVISIBLE (-3652 3400);
FORCEADD TAP..1
(-3650 3500);
FORCEPROP 3 LASTPIN (-3700 3500) SIG_NAME M_B_CPU0_SB_DQS_DP<8>
J 0
(-3690 3510);
DISPLAY 0.659574 (-3690 3510);
PAINT MONO (-3690 3510);
DISPLAY INVISIBLE (-3690 3510);
FORCEPROP 1 LASTPIN (-3700 3500) BN 8
J 0
(-3712 3508);
DISPLAY 0.489362 (-3712 3508);
PAINT GREEN (-3712 3508);
FORCEPROP 2 LAST CDS_LIB mstr_standard
J 0
(-3650 3500);
DISPLAY 0.723404 (-3650 3500);
PAINT MONO (-3650 3500);
DISPLAY INVISIBLE (-3650 3500);
FORCEPROP 1 LAST BODY_TYPE PLUMBING
J 0
(-3650 3550);
DISPLAY 0.872340 (-3650 3550);
PAINT GREEN (-3650 3550);
DISPLAY INVISIBLE (-3650 3550);
FORCEPROP 1 LAST HDL_TAP TRUE
J 0
(-3325 3375);
DISPLAY 0.872340 (-3325 3375);
DISPLAY INVISIBLE (-3325 3375);
FORCEPROP 1 LAST PATH I301
J 0
(-3652 3500);
DISPLAY 0.872340 (-3652 3500);
PAINT GREEN (-3652 3500);
DISPLAY INVISIBLE (-3652 3500);
FORCEADD TAP..1
(-3650 3600);
FORCEPROP 3 LASTPIN (-3700 3600) SIG_NAME M_B_CPU0_SB_DQS_DP<9>
J 0
(-3690 3610);
DISPLAY 0.659574 (-3690 3610);
PAINT MONO (-3690 3610);
DISPLAY INVISIBLE (-3690 3610);
FORCEPROP 1 LASTPIN (-3700 3600) BN 9
J 0
(-3712 3608);
DISPLAY 0.489362 (-3712 3608);
PAINT GREEN (-3712 3608);
FORCEPROP 2 LAST CDS_LIB mstr_standard
J 0
(-3650 3600);
DISPLAY 0.723404 (-3650 3600);
PAINT MONO (-3650 3600);
DISPLAY INVISIBLE (-3650 3600);
FORCEPROP 1 LAST BODY_TYPE PLUMBING
J 0
(-3650 3650);
DISPLAY 0.872340 (-3650 3650);
PAINT GREEN (-3650 3650);
DISPLAY INVISIBLE (-3650 3650);
FORCEPROP 1 LAST HDL_TAP TRUE
J 0
(-3325 3475);
DISPLAY 0.872340 (-3325 3475);
DISPLAY INVISIBLE (-3325 3475);
FORCEPROP 1 LAST PATH I302
J 0
(-3652 3600);
DISPLAY 0.872340 (-3652 3600);
PAINT GREEN (-3652 3600);
DISPLAY INVISIBLE (-3652 3600);
FORCEADD TAP..1
(-3450 3450);
FORCEPROP 3 LASTPIN (-3500 3450) SIG_NAME M_B_CPU0_SB_DQS_DN<8>
J 0
(-3490 3460);
DISPLAY 0.659574 (-3490 3460);
PAINT MONO (-3490 3460);
DISPLAY INVISIBLE (-3490 3460);
FORCEPROP 1 LASTPIN (-3500 3450) BN 8
J 0
(-3512 3458);
DISPLAY 0.489362 (-3512 3458);
PAINT GREEN (-3512 3458);
FORCEPROP 2 LAST CDS_LIB mstr_standard
J 0
(-3450 3450);
DISPLAY 0.723404 (-3450 3450);
PAINT MONO (-3450 3450);
DISPLAY INVISIBLE (-3450 3450);
FORCEPROP 1 LAST BODY_TYPE PLUMBING
J 0
(-3450 3500);
DISPLAY 0.872340 (-3450 3500);
PAINT GREEN (-3450 3500);
DISPLAY INVISIBLE (-3450 3500);
FORCEPROP 1 LAST HDL_TAP TRUE
J 0
(-3125 3325);
DISPLAY 0.872340 (-3125 3325);
DISPLAY INVISIBLE (-3125 3325);
FORCEPROP 1 LAST PATH I303
J 0
(-3452 3450);
DISPLAY 0.872340 (-3452 3450);
PAINT GREEN (-3452 3450);
DISPLAY INVISIBLE (-3452 3450);
FORCEADD TAP..1
(-3450 3550);
FORCEPROP 3 LASTPIN (-3500 3550) SIG_NAME M_B_CPU0_SB_DQS_DN<9>
J 0
(-3490 3560);
DISPLAY 0.659574 (-3490 3560);
PAINT MONO (-3490 3560);
DISPLAY INVISIBLE (-3490 3560);
FORCEPROP 1 LASTPIN (-3500 3550) BN 9
J 0
(-3512 3558);
DISPLAY 0.489362 (-3512 3558);
PAINT GREEN (-3512 3558);
FORCEPROP 2 LAST CDS_LIB mstr_standard
J 0
(-3450 3550);
DISPLAY 0.723404 (-3450 3550);
PAINT MONO (-3450 3550);
DISPLAY INVISIBLE (-3450 3550);
FORCEPROP 1 LAST BODY_TYPE PLUMBING
J 0
(-3450 3600);
DISPLAY 0.872340 (-3450 3600);
PAINT GREEN (-3450 3600);
DISPLAY INVISIBLE (-3450 3600);
FORCEPROP 1 LAST HDL_TAP TRUE
J 0
(-3125 3425);
DISPLAY 0.872340 (-3125 3425);
DISPLAY INVISIBLE (-3125 3425);
FORCEPROP 1 LAST PATH I304
J 0
(-3452 3550);
DISPLAY 0.872340 (-3452 3550);
PAINT GREEN (-3452 3550);
DISPLAY INVISIBLE (-3452 3550);
FORCEADD TAP..1
(-3650 3750);
FORCEPROP 3 LASTPIN (-3700 3750) SIG_NAME M_B_CPU0_SA_DQS_DP<0>
J 0
(-3690 3760);
DISPLAY 0.659574 (-3690 3760);
PAINT MONO (-3690 3760);
DISPLAY INVISIBLE (-3690 3760);
FORCEPROP 1 LASTPIN (-3700 3750) BN 0
J 0
(-3712 3758);
DISPLAY 0.489362 (-3712 3758);
PAINT GREEN (-3712 3758);
FORCEPROP 2 LAST CDS_LIB mstr_standard
J 0
(-3650 3750);
DISPLAY 0.723404 (-3650 3750);
PAINT MONO (-3650 3750);
DISPLAY INVISIBLE (-3650 3750);
FORCEPROP 1 LAST BODY_TYPE PLUMBING
J 0
(-3650 3800);
DISPLAY 0.872340 (-3650 3800);
PAINT GREEN (-3650 3800);
DISPLAY INVISIBLE (-3650 3800);
FORCEPROP 1 LAST HDL_TAP TRUE
J 0
(-3325 3625);
DISPLAY 0.872340 (-3325 3625);
DISPLAY INVISIBLE (-3325 3625);
FORCEPROP 1 LAST PATH I305
J 0
(-3652 3750);
DISPLAY 0.872340 (-3652 3750);
PAINT GREEN (-3652 3750);
DISPLAY INVISIBLE (-3652 3750);
FORCEADD TAP..1
(-3650 3850);
FORCEPROP 3 LASTPIN (-3700 3850) SIG_NAME M_B_CPU0_SA_DQS_DP<1>
J 0
(-3690 3860);
DISPLAY 0.659574 (-3690 3860);
PAINT MONO (-3690 3860);
DISPLAY INVISIBLE (-3690 3860);
FORCEPROP 1 LASTPIN (-3700 3850) BN 1
J 0
(-3712 3858);
DISPLAY 0.489362 (-3712 3858);
PAINT GREEN (-3712 3858);
FORCEPROP 2 LAST CDS_LIB mstr_standard
J 0
(-3650 3850);
DISPLAY 0.723404 (-3650 3850);
PAINT MONO (-3650 3850);
DISPLAY INVISIBLE (-3650 3850);
FORCEPROP 1 LAST BODY_TYPE PLUMBING
J 0
(-3650 3900);
DISPLAY 0.872340 (-3650 3900);
PAINT GREEN (-3650 3900);
DISPLAY INVISIBLE (-3650 3900);
FORCEPROP 1 LAST HDL_TAP TRUE
J 0
(-3325 3725);
DISPLAY 0.872340 (-3325 3725);
DISPLAY INVISIBLE (-3325 3725);
FORCEPROP 1 LAST PATH I306
J 0
(-3652 3850);
DISPLAY 0.872340 (-3652 3850);
PAINT GREEN (-3652 3850);
DISPLAY INVISIBLE (-3652 3850);
FORCEADD TAP..1
(-3450 3700);
FORCEPROP 3 LASTPIN (-3500 3700) SIG_NAME M_B_CPU0_SA_DQS_DN<0>
J 0
(-3490 3710);
DISPLAY 0.659574 (-3490 3710);
PAINT MONO (-3490 3710);
DISPLAY INVISIBLE (-3490 3710);
FORCEPROP 1 LASTPIN (-3500 3700) BN 0
J 0
(-3512 3708);
DISPLAY 0.489362 (-3512 3708);
PAINT GREEN (-3512 3708);
FORCEPROP 2 LAST CDS_LIB mstr_standard
J 0
(-3450 3700);
DISPLAY 0.723404 (-3450 3700);
PAINT MONO (-3450 3700);
DISPLAY INVISIBLE (-3450 3700);
FORCEPROP 1 LAST BODY_TYPE PLUMBING
J 0
(-3450 3750);
DISPLAY 0.872340 (-3450 3750);
PAINT GREEN (-3450 3750);
DISPLAY INVISIBLE (-3450 3750);
FORCEPROP 1 LAST HDL_TAP TRUE
J 0
(-3125 3575);
DISPLAY 0.872340 (-3125 3575);
DISPLAY INVISIBLE (-3125 3575);
FORCEPROP 1 LAST PATH I307
J 0
(-3452 3700);
DISPLAY 0.872340 (-3452 3700);
PAINT GREEN (-3452 3700);
DISPLAY INVISIBLE (-3452 3700);
FORCEADD TAP..1
(-3450 3800);
FORCEPROP 3 LASTPIN (-3500 3800) SIG_NAME M_B_CPU0_SA_DQS_DN<1>
J 0
(-3490 3810);
DISPLAY 0.659574 (-3490 3810);
PAINT MONO (-3490 3810);
DISPLAY INVISIBLE (-3490 3810);
FORCEPROP 1 LASTPIN (-3500 3800) BN 1
J 0
(-3512 3808);
DISPLAY 0.489362 (-3512 3808);
PAINT GREEN (-3512 3808);
FORCEPROP 2 LAST CDS_LIB mstr_standard
J 0
(-3450 3800);
DISPLAY 0.723404 (-3450 3800);
PAINT MONO (-3450 3800);
DISPLAY INVISIBLE (-3450 3800);
FORCEPROP 1 LAST BODY_TYPE PLUMBING
J 0
(-3450 3850);
DISPLAY 0.872340 (-3450 3850);
PAINT GREEN (-3450 3850);
DISPLAY INVISIBLE (-3450 3850);
FORCEPROP 1 LAST HDL_TAP TRUE
J 0
(-3125 3675);
DISPLAY 0.872340 (-3125 3675);
DISPLAY INVISIBLE (-3125 3675);
FORCEPROP 1 LAST PATH I308
J 0
(-3452 3800);
DISPLAY 0.872340 (-3452 3800);
PAINT GREEN (-3452 3800);
DISPLAY INVISIBLE (-3452 3800);
FORCEADD TAP..1
(-3650 3950);
FORCEPROP 3 LASTPIN (-3700 3950) SIG_NAME M_B_CPU0_SA_DQS_DP<2>
J 0
(-3690 3960);
DISPLAY 0.659574 (-3690 3960);
PAINT MONO (-3690 3960);
DISPLAY INVISIBLE (-3690 3960);
FORCEPROP 1 LASTPIN (-3700 3950) BN 2
J 0
(-3712 3958);
DISPLAY 0.489362 (-3712 3958);
PAINT GREEN (-3712 3958);
FORCEPROP 2 LAST CDS_LIB mstr_standard
J 0
(-3650 3950);
DISPLAY 0.723404 (-3650 3950);
PAINT MONO (-3650 3950);
DISPLAY INVISIBLE (-3650 3950);
FORCEPROP 1 LAST BODY_TYPE PLUMBING
J 0
(-3650 4000);
DISPLAY 0.872340 (-3650 4000);
PAINT GREEN (-3650 4000);
DISPLAY INVISIBLE (-3650 4000);
FORCEPROP 1 LAST HDL_TAP TRUE
J 0
(-3325 3825);
DISPLAY 0.872340 (-3325 3825);
DISPLAY INVISIBLE (-3325 3825);
FORCEPROP 1 LAST PATH I309
J 0
(-3652 3950);
DISPLAY 0.872340 (-3652 3950);
PAINT GREEN (-3652 3950);
DISPLAY INVISIBLE (-3652 3950);
FORCEADD TAP..1
(-3650 4050);
FORCEPROP 3 LASTPIN (-3700 4050) SIG_NAME M_B_CPU0_SA_DQS_DP<3>
J 0
(-3690 4060);
DISPLAY 0.659574 (-3690 4060);
PAINT MONO (-3690 4060);
DISPLAY INVISIBLE (-3690 4060);
FORCEPROP 1 LASTPIN (-3700 4050) BN 3
J 0
(-3712 4058);
DISPLAY 0.489362 (-3712 4058);
PAINT GREEN (-3712 4058);
FORCEPROP 2 LAST CDS_LIB mstr_standard
J 0
(-3650 4050);
DISPLAY 0.723404 (-3650 4050);
PAINT MONO (-3650 4050);
DISPLAY INVISIBLE (-3650 4050);
FORCEPROP 1 LAST BODY_TYPE PLUMBING
J 0
(-3650 4100);
DISPLAY 0.872340 (-3650 4100);
PAINT GREEN (-3650 4100);
DISPLAY INVISIBLE (-3650 4100);
FORCEPROP 1 LAST HDL_TAP TRUE
J 0
(-3325 3925);
DISPLAY 0.872340 (-3325 3925);
DISPLAY INVISIBLE (-3325 3925);
FORCEPROP 1 LAST PATH I310
J 0
(-3652 4050);
DISPLAY 0.872340 (-3652 4050);
PAINT GREEN (-3652 4050);
DISPLAY INVISIBLE (-3652 4050);
FORCEADD TAP..1
(-3450 3900);
FORCEPROP 3 LASTPIN (-3500 3900) SIG_NAME M_B_CPU0_SA_DQS_DN<2>
J 0
(-3490 3910);
DISPLAY 0.659574 (-3490 3910);
PAINT MONO (-3490 3910);
DISPLAY INVISIBLE (-3490 3910);
FORCEPROP 1 LASTPIN (-3500 3900) BN 2
J 0
(-3512 3908);
DISPLAY 0.489362 (-3512 3908);
PAINT GREEN (-3512 3908);
FORCEPROP 2 LAST CDS_LIB mstr_standard
J 0
(-3450 3900);
DISPLAY 0.723404 (-3450 3900);
PAINT MONO (-3450 3900);
DISPLAY INVISIBLE (-3450 3900);
FORCEPROP 1 LAST BODY_TYPE PLUMBING
J 0
(-3450 3950);
DISPLAY 0.872340 (-3450 3950);
PAINT GREEN (-3450 3950);
DISPLAY INVISIBLE (-3450 3950);
FORCEPROP 1 LAST HDL_TAP TRUE
J 0
(-3125 3775);
DISPLAY 0.872340 (-3125 3775);
DISPLAY INVISIBLE (-3125 3775);
FORCEPROP 1 LAST PATH I311
J 0
(-3452 3900);
DISPLAY 0.872340 (-3452 3900);
PAINT GREEN (-3452 3900);
DISPLAY INVISIBLE (-3452 3900);
FORCEADD TAP..1
(-3450 4000);
FORCEPROP 3 LASTPIN (-3500 4000) SIG_NAME M_B_CPU0_SA_DQS_DN<3>
J 0
(-3490 4010);
DISPLAY 0.659574 (-3490 4010);
PAINT MONO (-3490 4010);
DISPLAY INVISIBLE (-3490 4010);
FORCEPROP 1 LASTPIN (-3500 4000) BN 3
J 0
(-3512 4008);
DISPLAY 0.489362 (-3512 4008);
PAINT GREEN (-3512 4008);
FORCEPROP 2 LAST CDS_LIB mstr_standard
J 0
(-3450 4000);
DISPLAY 0.723404 (-3450 4000);
PAINT MONO (-3450 4000);
DISPLAY INVISIBLE (-3450 4000);
FORCEPROP 1 LAST BODY_TYPE PLUMBING
J 0
(-3450 4050);
DISPLAY 0.872340 (-3450 4050);
PAINT GREEN (-3450 4050);
DISPLAY INVISIBLE (-3450 4050);
FORCEPROP 1 LAST HDL_TAP TRUE
J 0
(-3125 3875);
DISPLAY 0.872340 (-3125 3875);
DISPLAY INVISIBLE (-3125 3875);
FORCEPROP 1 LAST PATH I312
J 0
(-3452 4000);
DISPLAY 0.872340 (-3452 4000);
PAINT GREEN (-3452 4000);
DISPLAY INVISIBLE (-3452 4000);
FORCEADD TAP..1
(-3450 4100);
FORCEPROP 3 LASTPIN (-3500 4100) SIG_NAME M_B_CPU0_SA_DQS_DN<4>
J 0
(-3490 4110);
DISPLAY 0.659574 (-3490 4110);
PAINT MONO (-3490 4110);
DISPLAY INVISIBLE (-3490 4110);
FORCEPROP 1 LASTPIN (-3500 4100) BN 4
J 0
(-3512 4108);
DISPLAY 0.489362 (-3512 4108);
PAINT GREEN (-3512 4108);
FORCEPROP 2 LAST CDS_LIB mstr_standard
J 0
(-3450 4100);
DISPLAY 0.723404 (-3450 4100);
PAINT MONO (-3450 4100);
DISPLAY INVISIBLE (-3450 4100);
FORCEPROP 1 LAST BODY_TYPE PLUMBING
J 0
(-3450 4150);
DISPLAY 0.872340 (-3450 4150);
PAINT GREEN (-3450 4150);
DISPLAY INVISIBLE (-3450 4150);
FORCEPROP 1 LAST HDL_TAP TRUE
J 0
(-3125 3975);
DISPLAY 0.872340 (-3125 3975);
DISPLAY INVISIBLE (-3125 3975);
FORCEPROP 1 LAST PATH I313
J 0
(-3452 4100);
DISPLAY 0.872340 (-3452 4100);
PAINT GREEN (-3452 4100);
DISPLAY INVISIBLE (-3452 4100);
FORCEADD OFFPAGE..2
(-2650 3600);
FORCEPROP 2 LAST $XR0 11 
J 0
(-2461 3600);
DISPLAY 0.638298 (-2461 3600);
PAINT MONO (-2461 3600);
FORCEPROP 2 LAST PATH I314
J 0
(-2350 3650);
DISPLAY 0.808511 (-2350 3650);
DISPLAY INVISIBLE (-2350 3650);
FORCEPROP 1 LAST COMMENT_BODY TRUE
J 0
(-2695 3505);
DISPLAY 0.872340 (-2695 3505);
PAINT GREEN (-2695 3505);
DISPLAY INVISIBLE (-2695 3505);
FORCEPROP 1 LAST OFFPAGE TRUE
J 0
(-2325 3475);
DISPLAY 0.723404 (-2325 3475);
PAINT GREEN (-2325 3475);
DISPLAY INVISIBLE (-2325 3475);
FORCEPROP 2 LAST CDS_LIB mstr_standard
J 0
(-2650 3600);
DISPLAY 0.723404 (-2650 3600);
PAINT MONO (-2650 3600);
DISPLAY INVISIBLE (-2650 3600);
FORCEADD OFFPAGE..2
(-2650 3650);
FORCEPROP 2 LAST $XR0 11 
J 0
(-2461 3650);
DISPLAY 0.638298 (-2461 3650);
PAINT MONO (-2461 3650);
FORCEPROP 2 LAST PATH I315
J 0
(-2350 3700);
DISPLAY 0.808511 (-2350 3700);
DISPLAY INVISIBLE (-2350 3700);
FORCEPROP 1 LAST COMMENT_BODY TRUE
J 0
(-2695 3555);
DISPLAY 0.872340 (-2695 3555);
PAINT GREEN (-2695 3555);
DISPLAY INVISIBLE (-2695 3555);
FORCEPROP 1 LAST OFFPAGE TRUE
J 0
(-2325 3525);
DISPLAY 0.723404 (-2325 3525);
PAINT GREEN (-2325 3525);
DISPLAY INVISIBLE (-2325 3525);
FORCEPROP 2 LAST CDS_LIB mstr_standard
J 0
(-2650 3650);
DISPLAY 0.723404 (-2650 3650);
PAINT MONO (-2650 3650);
DISPLAY INVISIBLE (-2650 3650);
FORCEADD TAP..1
(-3650 4150);
FORCEPROP 3 LASTPIN (-3700 4150) SIG_NAME M_B_CPU0_SA_DQS_DP<4>
J 0
(-3690 4160);
DISPLAY 0.659574 (-3690 4160);
PAINT MONO (-3690 4160);
DISPLAY INVISIBLE (-3690 4160);
FORCEPROP 1 LASTPIN (-3700 4150) BN 4
J 0
(-3712 4158);
DISPLAY 0.489362 (-3712 4158);
PAINT GREEN (-3712 4158);
FORCEPROP 2 LAST CDS_LIB mstr_standard
J 0
(-3650 4150);
DISPLAY 0.723404 (-3650 4150);
PAINT MONO (-3650 4150);
DISPLAY INVISIBLE (-3650 4150);
FORCEPROP 1 LAST BODY_TYPE PLUMBING
J 0
(-3650 4200);
DISPLAY 0.872340 (-3650 4200);
PAINT GREEN (-3650 4200);
DISPLAY INVISIBLE (-3650 4200);
FORCEPROP 1 LAST HDL_TAP TRUE
J 0
(-3325 4025);
DISPLAY 0.872340 (-3325 4025);
DISPLAY INVISIBLE (-3325 4025);
FORCEPROP 1 LAST PATH I316
J 0
(-3652 4150);
DISPLAY 0.872340 (-3652 4150);
PAINT GREEN (-3652 4150);
DISPLAY INVISIBLE (-3652 4150);
FORCEADD TAP..1
(-3650 4250);
FORCEPROP 3 LASTPIN (-3700 4250) SIG_NAME M_B_CPU0_SA_DQS_DP<5>
J 0
(-3690 4260);
DISPLAY 0.659574 (-3690 4260);
PAINT MONO (-3690 4260);
DISPLAY INVISIBLE (-3690 4260);
FORCEPROP 1 LASTPIN (-3700 4250) BN 5
J 0
(-3712 4258);
DISPLAY 0.489362 (-3712 4258);
PAINT GREEN (-3712 4258);
FORCEPROP 2 LAST CDS_LIB mstr_standard
J 0
(-3650 4250);
DISPLAY 0.723404 (-3650 4250);
PAINT MONO (-3650 4250);
DISPLAY INVISIBLE (-3650 4250);
FORCEPROP 1 LAST BODY_TYPE PLUMBING
J 0
(-3650 4300);
DISPLAY 0.872340 (-3650 4300);
PAINT GREEN (-3650 4300);
DISPLAY INVISIBLE (-3650 4300);
FORCEPROP 1 LAST HDL_TAP TRUE
J 0
(-3325 4125);
DISPLAY 0.872340 (-3325 4125);
DISPLAY INVISIBLE (-3325 4125);
FORCEPROP 1 LAST PATH I317
J 0
(-3652 4250);
DISPLAY 0.872340 (-3652 4250);
PAINT GREEN (-3652 4250);
DISPLAY INVISIBLE (-3652 4250);
FORCEADD TAP..1
(-3650 4350);
FORCEPROP 3 LASTPIN (-3700 4350) SIG_NAME M_B_CPU0_SA_DQS_DP<6>
J 0
(-3690 4360);
DISPLAY 0.659574 (-3690 4360);
PAINT MONO (-3690 4360);
DISPLAY INVISIBLE (-3690 4360);
FORCEPROP 1 LASTPIN (-3700 4350) BN 6
J 0
(-3712 4358);
DISPLAY 0.489362 (-3712 4358);
PAINT GREEN (-3712 4358);
FORCEPROP 2 LAST CDS_LIB mstr_standard
J 0
(-3650 4350);
DISPLAY 0.723404 (-3650 4350);
PAINT MONO (-3650 4350);
DISPLAY INVISIBLE (-3650 4350);
FORCEPROP 1 LAST BODY_TYPE PLUMBING
J 0
(-3650 4400);
DISPLAY 0.872340 (-3650 4400);
PAINT GREEN (-3650 4400);
DISPLAY INVISIBLE (-3650 4400);
FORCEPROP 1 LAST HDL_TAP TRUE
J 0
(-3325 4225);
DISPLAY 0.872340 (-3325 4225);
DISPLAY INVISIBLE (-3325 4225);
FORCEPROP 1 LAST PATH I318
J 0
(-3652 4350);
DISPLAY 0.872340 (-3652 4350);
PAINT GREEN (-3652 4350);
DISPLAY INVISIBLE (-3652 4350);
FORCEADD TAP..1
(-3450 4400);
FORCEPROP 3 LASTPIN (-3500 4400) SIG_NAME M_B_CPU0_SA_DQS_DN<7>
J 0
(-3490 4410);
DISPLAY 0.659574 (-3490 4410);
PAINT MONO (-3490 4410);
DISPLAY INVISIBLE (-3490 4410);
FORCEPROP 1 LASTPIN (-3500 4400) BN 7
J 0
(-3512 4408);
DISPLAY 0.489362 (-3512 4408);
PAINT GREEN (-3512 4408);
FORCEPROP 2 LAST CDS_LIB mstr_standard
J 0
(-3450 4400);
DISPLAY 0.723404 (-3450 4400);
PAINT MONO (-3450 4400);
DISPLAY INVISIBLE (-3450 4400);
FORCEPROP 1 LAST BODY_TYPE PLUMBING
J 0
(-3450 4450);
DISPLAY 0.872340 (-3450 4450);
PAINT GREEN (-3450 4450);
DISPLAY INVISIBLE (-3450 4450);
FORCEPROP 1 LAST HDL_TAP TRUE
J 0
(-3125 4275);
DISPLAY 0.872340 (-3125 4275);
DISPLAY INVISIBLE (-3125 4275);
FORCEPROP 1 LAST PATH I319
J 0
(-3452 4400);
DISPLAY 0.872340 (-3452 4400);
PAINT GREEN (-3452 4400);
DISPLAY INVISIBLE (-3452 4400);
FORCEADD TAP..1
(-3450 4300);
FORCEPROP 3 LASTPIN (-3500 4300) SIG_NAME M_B_CPU0_SA_DQS_DN<6>
J 0
(-3490 4310);
DISPLAY 0.659574 (-3490 4310);
PAINT MONO (-3490 4310);
DISPLAY INVISIBLE (-3490 4310);
FORCEPROP 1 LASTPIN (-3500 4300) BN 6
J 0
(-3512 4308);
DISPLAY 0.489362 (-3512 4308);
PAINT GREEN (-3512 4308);
FORCEPROP 2 LAST CDS_LIB mstr_standard
J 0
(-3450 4300);
DISPLAY 0.723404 (-3450 4300);
PAINT MONO (-3450 4300);
DISPLAY INVISIBLE (-3450 4300);
FORCEPROP 1 LAST BODY_TYPE PLUMBING
J 0
(-3450 4350);
DISPLAY 0.872340 (-3450 4350);
PAINT GREEN (-3450 4350);
DISPLAY INVISIBLE (-3450 4350);
FORCEPROP 1 LAST HDL_TAP TRUE
J 0
(-3125 4175);
DISPLAY 0.872340 (-3125 4175);
DISPLAY INVISIBLE (-3125 4175);
FORCEPROP 1 LAST PATH I320
J 0
(-3452 4300);
DISPLAY 0.872340 (-3452 4300);
PAINT GREEN (-3452 4300);
DISPLAY INVISIBLE (-3452 4300);
FORCEADD TAP..1
(-3450 4200);
FORCEPROP 3 LASTPIN (-3500 4200) SIG_NAME M_B_CPU0_SA_DQS_DN<5>
J 0
(-3490 4210);
DISPLAY 0.659574 (-3490 4210);
PAINT MONO (-3490 4210);
DISPLAY INVISIBLE (-3490 4210);
FORCEPROP 1 LASTPIN (-3500 4200) BN 5
J 0
(-3512 4208);
DISPLAY 0.489362 (-3512 4208);
PAINT GREEN (-3512 4208);
FORCEPROP 2 LAST CDS_LIB mstr_standard
J 0
(-3450 4200);
DISPLAY 0.723404 (-3450 4200);
PAINT MONO (-3450 4200);
DISPLAY INVISIBLE (-3450 4200);
FORCEPROP 1 LAST BODY_TYPE PLUMBING
J 0
(-3450 4250);
DISPLAY 0.872340 (-3450 4250);
PAINT GREEN (-3450 4250);
DISPLAY INVISIBLE (-3450 4250);
FORCEPROP 1 LAST HDL_TAP TRUE
J 0
(-3125 4075);
DISPLAY 0.872340 (-3125 4075);
DISPLAY INVISIBLE (-3125 4075);
FORCEPROP 1 LAST PATH I321
J 0
(-3452 4200);
DISPLAY 0.872340 (-3452 4200);
PAINT GREEN (-3452 4200);
DISPLAY INVISIBLE (-3452 4200);
FORCEADD TAP..1
(-3650 4450);
FORCEPROP 3 LASTPIN (-3700 4450) SIG_NAME M_B_CPU0_SA_DQS_DP<7>
J 0
(-3690 4460);
DISPLAY 0.659574 (-3690 4460);
PAINT MONO (-3690 4460);
DISPLAY INVISIBLE (-3690 4460);
FORCEPROP 1 LASTPIN (-3700 4450) BN 7
J 0
(-3712 4458);
DISPLAY 0.489362 (-3712 4458);
PAINT GREEN (-3712 4458);
FORCEPROP 2 LAST CDS_LIB mstr_standard
J 0
(-3650 4450);
DISPLAY 0.723404 (-3650 4450);
PAINT MONO (-3650 4450);
DISPLAY INVISIBLE (-3650 4450);
FORCEPROP 1 LAST BODY_TYPE PLUMBING
J 0
(-3650 4500);
DISPLAY 0.872340 (-3650 4500);
PAINT GREEN (-3650 4500);
DISPLAY INVISIBLE (-3650 4500);
FORCEPROP 1 LAST HDL_TAP TRUE
J 0
(-3325 4325);
DISPLAY 0.872340 (-3325 4325);
DISPLAY INVISIBLE (-3325 4325);
FORCEPROP 1 LAST PATH I322
J 0
(-3652 4450);
DISPLAY 0.872340 (-3652 4450);
PAINT GREEN (-3652 4450);
DISPLAY INVISIBLE (-3652 4450);
FORCEADD TAP..1
(-3650 4550);
FORCEPROP 3 LASTPIN (-3700 4550) SIG_NAME M_B_CPU0_SA_DQS_DP<8>
J 0
(-3690 4560);
DISPLAY 0.659574 (-3690 4560);
PAINT MONO (-3690 4560);
DISPLAY INVISIBLE (-3690 4560);
FORCEPROP 1 LASTPIN (-3700 4550) BN 8
J 0
(-3712 4558);
DISPLAY 0.489362 (-3712 4558);
PAINT GREEN (-3712 4558);
FORCEPROP 2 LAST CDS_LIB mstr_standard
J 0
(-3650 4550);
DISPLAY 0.723404 (-3650 4550);
PAINT MONO (-3650 4550);
DISPLAY INVISIBLE (-3650 4550);
FORCEPROP 1 LAST BODY_TYPE PLUMBING
J 0
(-3650 4600);
DISPLAY 0.872340 (-3650 4600);
PAINT GREEN (-3650 4600);
DISPLAY INVISIBLE (-3650 4600);
FORCEPROP 1 LAST HDL_TAP TRUE
J 0
(-3325 4425);
DISPLAY 0.872340 (-3325 4425);
DISPLAY INVISIBLE (-3325 4425);
FORCEPROP 1 LAST PATH I323
J 0
(-3652 4550);
DISPLAY 0.872340 (-3652 4550);
PAINT GREEN (-3652 4550);
DISPLAY INVISIBLE (-3652 4550);
FORCEADD TAP..1
(-3650 4650);
FORCEPROP 3 LASTPIN (-3700 4650) SIG_NAME M_B_CPU0_SA_DQS_DP<9>
J 0
(-3690 4660);
DISPLAY 0.659574 (-3690 4660);
PAINT MONO (-3690 4660);
DISPLAY INVISIBLE (-3690 4660);
FORCEPROP 1 LASTPIN (-3700 4650) BN 9
J 0
(-3712 4658);
DISPLAY 0.489362 (-3712 4658);
PAINT GREEN (-3712 4658);
FORCEPROP 2 LAST CDS_LIB mstr_standard
J 0
(-3650 4650);
DISPLAY 0.723404 (-3650 4650);
PAINT MONO (-3650 4650);
DISPLAY INVISIBLE (-3650 4650);
FORCEPROP 1 LAST BODY_TYPE PLUMBING
J 0
(-3650 4700);
DISPLAY 0.872340 (-3650 4700);
PAINT GREEN (-3650 4700);
DISPLAY INVISIBLE (-3650 4700);
FORCEPROP 1 LAST HDL_TAP TRUE
J 0
(-3325 4525);
DISPLAY 0.872340 (-3325 4525);
DISPLAY INVISIBLE (-3325 4525);
FORCEPROP 1 LAST PATH I324
J 0
(-3652 4650);
DISPLAY 0.872340 (-3652 4650);
PAINT GREEN (-3652 4650);
DISPLAY INVISIBLE (-3652 4650);
FORCEADD TAP..1
(-3450 4600);
FORCEPROP 3 LASTPIN (-3500 4600) SIG_NAME M_B_CPU0_SA_DQS_DN<9>
J 0
(-3490 4610);
DISPLAY 0.659574 (-3490 4610);
PAINT MONO (-3490 4610);
DISPLAY INVISIBLE (-3490 4610);
FORCEPROP 1 LASTPIN (-3500 4600) BN 9
J 0
(-3512 4608);
DISPLAY 0.489362 (-3512 4608);
PAINT GREEN (-3512 4608);
FORCEPROP 2 LAST CDS_LIB mstr_standard
J 0
(-3450 4600);
DISPLAY 0.723404 (-3450 4600);
PAINT MONO (-3450 4600);
DISPLAY INVISIBLE (-3450 4600);
FORCEPROP 1 LAST BODY_TYPE PLUMBING
J 0
(-3450 4650);
DISPLAY 0.872340 (-3450 4650);
PAINT GREEN (-3450 4650);
DISPLAY INVISIBLE (-3450 4650);
FORCEPROP 1 LAST HDL_TAP TRUE
J 0
(-3125 4475);
DISPLAY 0.872340 (-3125 4475);
DISPLAY INVISIBLE (-3125 4475);
FORCEPROP 1 LAST PATH I325
J 0
(-3452 4600);
DISPLAY 0.872340 (-3452 4600);
PAINT GREEN (-3452 4600);
DISPLAY INVISIBLE (-3452 4600);
FORCEADD TAP..1
(-3450 4500);
FORCEPROP 3 LASTPIN (-3500 4500) SIG_NAME M_B_CPU0_SA_DQS_DN<8>
J 0
(-3490 4510);
DISPLAY 0.659574 (-3490 4510);
PAINT MONO (-3490 4510);
DISPLAY INVISIBLE (-3490 4510);
FORCEPROP 1 LASTPIN (-3500 4500) BN 8
J 0
(-3512 4508);
DISPLAY 0.489362 (-3512 4508);
PAINT GREEN (-3512 4508);
FORCEPROP 2 LAST CDS_LIB mstr_standard
J 0
(-3450 4500);
DISPLAY 0.723404 (-3450 4500);
PAINT MONO (-3450 4500);
DISPLAY INVISIBLE (-3450 4500);
FORCEPROP 1 LAST BODY_TYPE PLUMBING
J 0
(-3450 4550);
DISPLAY 0.872340 (-3450 4550);
PAINT GREEN (-3450 4550);
DISPLAY INVISIBLE (-3450 4550);
FORCEPROP 1 LAST HDL_TAP TRUE
J 0
(-3125 4375);
DISPLAY 0.872340 (-3125 4375);
DISPLAY INVISIBLE (-3125 4375);
FORCEPROP 1 LAST PATH I326
J 0
(-3452 4500);
DISPLAY 0.872340 (-3452 4500);
PAINT GREEN (-3452 4500);
DISPLAY INVISIBLE (-3452 4500);
FORCEADD OFFPAGE..2
(-2650 4650);
FORCEPROP 2 LAST $XR0 11 
J 0
(-2461 4650);
DISPLAY 0.638298 (-2461 4650);
PAINT MONO (-2461 4650);
FORCEPROP 2 LAST PATH I327
J 0
(-2350 4700);
DISPLAY 0.808511 (-2350 4700);
DISPLAY INVISIBLE (-2350 4700);
FORCEPROP 1 LAST COMMENT_BODY TRUE
J 0
(-2695 4555);
DISPLAY 0.872340 (-2695 4555);
PAINT GREEN (-2695 4555);
DISPLAY INVISIBLE (-2695 4555);
FORCEPROP 1 LAST OFFPAGE TRUE
J 0
(-2325 4525);
DISPLAY 0.723404 (-2325 4525);
PAINT GREEN (-2325 4525);
DISPLAY INVISIBLE (-2325 4525);
FORCEPROP 2 LAST CDS_LIB mstr_standard
J 0
(-2650 4650);
DISPLAY 0.723404 (-2650 4650);
PAINT MONO (-2650 4650);
DISPLAY INVISIBLE (-2650 4650);
FORCEADD OFFPAGE..2
(-2650 4700);
FORCEPROP 2 LAST $XR0 11 
J 0
(-2461 4700);
DISPLAY 0.638298 (-2461 4700);
PAINT MONO (-2461 4700);
FORCEPROP 2 LAST PATH I328
J 0
(-2350 4750);
DISPLAY 0.808511 (-2350 4750);
DISPLAY INVISIBLE (-2350 4750);
FORCEPROP 1 LAST COMMENT_BODY TRUE
J 0
(-2695 4605);
DISPLAY 0.872340 (-2695 4605);
PAINT GREEN (-2695 4605);
DISPLAY INVISIBLE (-2695 4605);
FORCEPROP 1 LAST OFFPAGE TRUE
J 0
(-2325 4575);
DISPLAY 0.723404 (-2325 4575);
PAINT GREEN (-2325 4575);
DISPLAY INVISIBLE (-2325 4575);
FORCEPROP 2 LAST CDS_LIB mstr_standard
J 0
(-2650 4700);
DISPLAY 0.723404 (-2650 4700);
PAINT MONO (-2650 4700);
DISPLAY INVISIBLE (-2650 4700);
FORCEADD GND..1
(-6650 1175);
FORCEPROP 3 LASTPIN (-6650 1225) SIG_NAME GND\g
J 0
(-6640 1235);
DISPLAY 0.659574 (-6640 1235);
PAINT MONO (-6640 1235);
DISPLAY INVISIBLE (-6640 1235);
FORCEPROP 2 LAST BOM_COST MEM
J 0
(-6750 1250);
DISPLAY 0.808511 (-6750 1250);
DISPLAY INVISIBLE (-6750 1250);
FORCEPROP 2 LAST CDS_LIB mstr_symbols
J 0
(-6650 1175);
DISPLAY 0.808511 (-6650 1175);
DISPLAY INVISIBLE (-6650 1175);
FORCEPROP 1 LAST SIZE 1B
J 0
(-6575 1125);
DISPLAY 0.851064 (-6575 1125);
PAINT GREEN (-6575 1125);
DISPLAY INVISIBLE (-6575 1125);
FORCEPROP 1 LAST BODY_TYPE PLUMBING
J 0
(-6695 1132);
DISPLAY 0.340426 (-6695 1132);
PAINT GREEN (-6695 1132);
DISPLAY INVISIBLE (-6695 1132);
FORCEPROP 1 LAST PATH I332
J 0
(-6575 1175);
DISPLAY 0.872340 (-6575 1175);
PAINT GREEN (-6575 1175);
DISPLAY INVISIBLE (-6575 1175);
FORCEPROP 1 LAST VOLTAGE 0.0
J 0
(-6695 1132);
DISPLAY 0.723404 (-6695 1132);
PAINT SKYBLUE (-6695 1132);
DISPLAY INVISIBLE (-6695 1132);
FORCEPROP 1 LAST HDL_POWER GND
J 0
(-6650 1325);
DISPLAY 0.851064 (-6650 1325);
PAINT GREEN (-6650 1325);
DISPLAY INVISIBLE (-6650 1325);
FORCEADD OFFPAGE..5
(-7425 1575);
FORCEPROP 2 LAST $XR0 86 
J 0
(-7649 1575);
DISPLAY 0.638298 (-7649 1575);
PAINT MONO (-7649 1575);
FORCEPROP 2 LAST PATH I333
J 0
(-7375 1650);
DISPLAY 0.808511 (-7375 1650);
DISPLAY INVISIBLE (-7375 1650);
FORCEPROP 1 LAST COMMENT_BODY TRUE
J 0
(-7325 1500);
DISPLAY 0.872340 (-7325 1500);
PAINT GREEN (-7325 1500);
DISPLAY INVISIBLE (-7325 1500);
FORCEPROP 1 LAST OFFPAGE TRUE
J 0
(-7100 1450);
DISPLAY 0.872340 (-7100 1450);
PAINT GREEN (-7100 1450);
DISPLAY INVISIBLE (-7100 1450);
FORCEPROP 2 LAST BOM_COST MEM
J 0
(-7500 1650);
DISPLAY 0.808511 (-7500 1650);
DISPLAY INVISIBLE (-7500 1650);
FORCEPROP 2 LAST CDS_LIB mstr_standard
J 0
(-7425 1575);
DISPLAY 0.808511 (-7425 1575);
DISPLAY INVISIBLE (-7425 1575);
FORCEADD OFFPAGE..1
(-8550 3025);
FORCEPROP 2 LAST $XR0 86 
J 0
(-8771 3025);
DISPLAY 0.638298 (-8771 3025);
PAINT MONO (-8771 3025);
FORCEPROP 2 LAST PATH I334
J 0
(-8500 3100);
DISPLAY 0.808511 (-8500 3100);
DISPLAY INVISIBLE (-8500 3100);
FORCEPROP 1 LAST COMMENT_BODY TRUE
J 0
(-8425 2925);
DISPLAY 0.872340 (-8425 2925);
PAINT GREEN (-8425 2925);
DISPLAY INVISIBLE (-8425 2925);
FORCEPROP 1 LAST OFFPAGE TRUE
J 0
(-8225 2900);
DISPLAY 0.872340 (-8225 2900);
PAINT GREEN (-8225 2900);
DISPLAY INVISIBLE (-8225 2900);
FORCEPROP 2 LAST CDS_LIB mstr_standard
J 0
(-8550 3025);
DISPLAY 0.808511 (-8550 3025);
DISPLAY INVISIBLE (-8550 3025);
FORCEADD Q_RES..2
(-6650 1400);
FORCEPROP 1 LAST LOCATION R761
J 0
(-6605 1525);
DISPLAY 0.489362 (-6605 1525);
PAINT SKYBLUE (-6605 1525);
FORCEPROP 0 LAST $SEC 1
J 0
(-6600 1575);
DISPLAY 0.680851 (-6600 1575);
PAINT MONO (-6600 1575);
DISPLAY INVISIBLE (-6600 1575);
FORCEPROP 0 LAST CDS_SEC 1
J 0
(-6600 1575);
DISPLAY 1.021277 (-6600 1575);
DISPLAY INVISIBLE (-6600 1575);
FORCEPROP 1 LASTPIN (-6650 1500) $PN 1
J 0
(-6645 1462);
DISPLAY 0.489362 (-6645 1462);
PAINT MONO (-6645 1462);
FORCEPROP 1 LASTPIN (-6650 1300) $PN 2
J 0
(-6645 1310);
DISPLAY 0.489362 (-6645 1310);
PAINT MONO (-6645 1310);
FORCEPROP 1 LAST WATTAGE 1/16W
J 0
(-6610 1375);
DISPLAY 0.489362 (-6610 1375);
PAINT SKYBLUE (-6610 1375);
FORCEPROP 1 LAST MATERIAL CHIP
J 0
(-6610 1325);
DISPLAY 0.489362 (-6610 1325);
PAINT SKYBLUE (-6610 1325);
FORCEPROP 1 LAST TOLERANCE 1%
J 0
(-6605 1425);
DISPLAY 0.489362 (-6605 1425);
PAINT SKYBLUE (-6605 1425);
FORCEPROP 1 LAST VALUE 15.4K
J 0
(-6605 1475);
DISPLAY 0.489362 (-6605 1475);
PAINT SKYBLUE (-6605 1475);
FORCEPROP 1 LAST PART_NUMBER CS31542FB02
J 0
(-6610 1275);
DISPLAY 0.489362 (-6610 1275);
PAINT SKYBLUE (-6610 1275);
FORCEPROP 1 LAST PACK_TYPE 0402LF
J 0
(-6610 1225);
DISPLAY 0.489362 (-6610 1225);
PAINT SKYBLUE (-6610 1225);
FORCEPROP 2 LAST CDS_LIB pure_quanta
J 0
(-6650 1400);
DISPLAY INVISIBLE (-6650 1400);
FORCEPROP 1 LAST PATH I349
J 0
(-6600 1575);
DISPLAY 0.978723 (-6600 1575);
PAINT WHITE (-6600 1575);
DISPLAY INVISIBLE (-6600 1575);
FORCEADD SCONN288_DDR506112002KQ..1
(-7100 3775);
FORCEPROP 1 LAST LOCATION J15
J 0
(-7550 5850);
DISPLAY 0.574468 (-7550 5850);
PAINT SKYBLUE (-7550 5850);
FORCEPROP 0 LAST $SEC 1
J 0
(-7550 6000);
DISPLAY 0.680851 (-7550 6000);
PAINT MONO (-7550 6000);
DISPLAY INVISIBLE (-7550 6000);
FORCEPROP 2 LAST CDS_SEC 1
J 0
(-7550 6000);
DISPLAY 1.021277 (-7550 6000);
DISPLAY INVISIBLE (-7550 6000);
FORCEPROP 0 LASTPIN (-7700 3175) $PN 62
J 2
(-7710 3185);
DISPLAY 0.680851 (-7710 3185);
PAINT MONO (-7710 3185);
FORCEPROP 0 LASTPIN (-7700 5225) $PN 66
J 2
(-7710 5235);
DISPLAY 0.680851 (-7710 5235);
PAINT MONO (-7710 5235);
FORCEPROP 0 LASTPIN (-7700 4825) $PN 76
J 2
(-7710 4835);
DISPLAY 0.680851 (-7710 4835);
PAINT MONO (-7710 4835);
FORCEPROP 0 LASTPIN (-7700 5275) $PN 211
J 2
(-7710 5285);
DISPLAY 0.680851 (-7710 5285);
PAINT MONO (-7710 5285);
FORCEPROP 0 LASTPIN (-7700 4875) $PN 221
J 2
(-7710 4885);
DISPLAY 0.680851 (-7710 4885);
PAINT MONO (-7710 4885);
FORCEPROP 0 LASTPIN (-7700 5325) $PN 68
J 2
(-7710 5335);
DISPLAY 0.680851 (-7710 5335);
PAINT MONO (-7710 5335);
FORCEPROP 0 LASTPIN (-7700 4925) $PN 78
J 2
(-7710 4935);
DISPLAY 0.680851 (-7710 4935);
PAINT MONO (-7710 4935);
FORCEPROP 0 LASTPIN (-7700 5375) $PN 213
J 2
(-7710 5385);
DISPLAY 0.680851 (-7710 5385);
PAINT MONO (-7710 5385);
FORCEPROP 0 LASTPIN (-7700 4975) $PN 223
J 2
(-7710 4985);
DISPLAY 0.680851 (-7710 4985);
PAINT MONO (-7710 4985);
FORCEPROP 0 LASTPIN (-7700 5425) $PN 70
J 2
(-7710 5435);
DISPLAY 0.680851 (-7710 5435);
PAINT MONO (-7710 5435);
FORCEPROP 0 LASTPIN (-7700 5025) $PN 80
J 2
(-7710 5035);
DISPLAY 0.680851 (-7710 5035);
PAINT MONO (-7710 5035);
FORCEPROP 0 LASTPIN (-7700 5475) $PN 215
J 2
(-7710 5485);
DISPLAY 0.680851 (-7710 5485);
PAINT MONO (-7710 5485);
FORCEPROP 0 LASTPIN (-7700 5075) $PN 225
J 2
(-7710 5085);
DISPLAY 0.680851 (-7710 5085);
PAINT MONO (-7710 5085);
FORCEPROP 0 LASTPIN (-7700 5525) $PN 72
J 2
(-7710 5535);
DISPLAY 0.680851 (-7710 5535);
PAINT MONO (-7710 5535);
FORCEPROP 0 LASTPIN (-7700 5125) $PN 82
J 2
(-7710 5135);
DISPLAY 0.680851 (-7710 5135);
PAINT MONO (-7710 5135);
FORCEPROP 0 LASTPIN (-7700 3775) $PN 51
J 2
(-7710 3785);
DISPLAY 0.680851 (-7710 3785);
PAINT MONO (-7710 3785);
FORCEPROP 0 LASTPIN (-7700 3325) $PN 96
J 2
(-7710 3335);
DISPLAY 0.680851 (-7710 3335);
PAINT MONO (-7710 3335);
FORCEPROP 0 LASTPIN (-7700 3825) $PN 53
J 2
(-7710 3835);
DISPLAY 0.680851 (-7710 3835);
PAINT MONO (-7710 3835);
FORCEPROP 0 LASTPIN (-7700 3375) $PN 98
J 2
(-7710 3385);
DISPLAY 0.680851 (-7710 3385);
PAINT MONO (-7710 3385);
FORCEPROP 0 LASTPIN (-7700 3875) $PN 196
J 2
(-7710 3885);
DISPLAY 0.680851 (-7710 3885);
PAINT MONO (-7710 3885);
FORCEPROP 0 LASTPIN (-7700 3425) $PN 241
J 2
(-7710 3435);
DISPLAY 0.680851 (-7710 3435);
PAINT MONO (-7710 3435);
FORCEPROP 0 LASTPIN (-7700 3925) $PN 198
J 2
(-7710 3935);
DISPLAY 0.680851 (-7710 3935);
PAINT MONO (-7710 3935);
FORCEPROP 0 LASTPIN (-7700 3475) $PN 243
J 2
(-7710 3485);
DISPLAY 0.680851 (-7710 3485);
PAINT MONO (-7710 3485);
FORCEPROP 0 LASTPIN (-7700 3975) $PN 58
J 2
(-7710 3985);
DISPLAY 0.680851 (-7710 3985);
PAINT MONO (-7710 3985);
FORCEPROP 0 LASTPIN (-7700 3525) $PN 89
J 2
(-7710 3535);
DISPLAY 0.680851 (-7710 3535);
PAINT MONO (-7710 3535);
FORCEPROP 0 LASTPIN (-7700 4025) $PN 60
J 2
(-7710 4035);
DISPLAY 0.680851 (-7710 4035);
PAINT MONO (-7710 4035);
FORCEPROP 0 LASTPIN (-7700 3575) $PN 91
J 2
(-7710 3585);
DISPLAY 0.680851 (-7710 3585);
PAINT MONO (-7710 3585);
FORCEPROP 0 LASTPIN (-7700 4075) $PN 203
J 2
(-7710 4085);
DISPLAY 0.680851 (-7710 4085);
PAINT MONO (-7710 4085);
FORCEPROP 0 LASTPIN (-7700 3625) $PN 234
J 2
(-7710 3635);
DISPLAY 0.680851 (-7710 3635);
PAINT MONO (-7710 3635);
FORCEPROP 0 LASTPIN (-7700 4125) $PN 205
J 2
(-7710 4135);
DISPLAY 0.680851 (-7710 4135);
PAINT MONO (-7710 4135);
FORCEPROP 0 LASTPIN (-7700 3675) $PN 236
J 2
(-7710 3685);
DISPLAY 0.680851 (-7710 3685);
PAINT MONO (-7710 3685);
FORCEPROP 0 LASTPIN (-7700 4225) $PN 218
J 2
(-7710 4235);
DISPLAY 0.680851 (-7710 4235);
PAINT MONO (-7710 4235);
FORCEPROP 0 LASTPIN (-7700 4275) $PN 217
J 2
(-7710 4285);
DISPLAY 0.680851 (-7710 4285);
PAINT MONO (-7710 4285);
FORCEPROP 0 LASTPIN (-7700 4525) $PN 64
J 2
(-7710 4535);
DISPLAY 0.680851 (-7710 4535);
PAINT MONO (-7710 4535);
FORCEPROP 0 LASTPIN (-7700 4375) $PN 84
J 2
(-7710 4385);
DISPLAY 0.680851 (-7710 4385);
PAINT MONO (-7710 4385);
FORCEPROP 0 LASTPIN (-7700 4575) $PN 209
J 2
(-7710 4585);
DISPLAY 0.680851 (-7710 4585);
PAINT MONO (-7710 4585);
FORCEPROP 0 LASTPIN (-7700 4425) $PN 229
J 2
(-7710 4435);
DISPLAY 0.680851 (-7710 4435);
PAINT MONO (-7710 4435);
FORCEPROP 0 LASTPIN (-6500 3975) $PN 7
J 0
(-6490 3985);
DISPLAY 0.680851 (-6490 3985);
PAINT MONO (-6490 3985);
FORCEPROP 0 LASTPIN (-6500 2325) $PN 100
J 0
(-6490 2335);
DISPLAY 0.680851 (-6490 2335);
PAINT MONO (-6490 2335);
FORCEPROP 0 LASTPIN (-6500 4025) $PN 9
J 0
(-6490 4035);
DISPLAY 0.680851 (-6490 4035);
PAINT MONO (-6490 4035);
FORCEPROP 0 LASTPIN (-6500 2375) $PN 102
J 0
(-6490 2385);
DISPLAY 0.680851 (-6490 2385);
PAINT MONO (-6490 2385);
FORCEPROP 0 LASTPIN (-6500 4075) $PN 152
J 0
(-6490 4085);
DISPLAY 0.680851 (-6490 4085);
PAINT MONO (-6490 4085);
FORCEPROP 0 LASTPIN (-6500 2425) $PN 245
J 0
(-6490 2435);
DISPLAY 0.680851 (-6490 2435);
PAINT MONO (-6490 2435);
FORCEPROP 0 LASTPIN (-6500 4125) $PN 154
J 0
(-6490 4135);
DISPLAY 0.680851 (-6490 4135);
PAINT MONO (-6490 4135);
FORCEPROP 0 LASTPIN (-6500 2475) $PN 247
J 0
(-6490 2485);
DISPLAY 0.680851 (-6490 2485);
PAINT MONO (-6490 2485);
FORCEPROP 0 LASTPIN (-6500 4175) $PN 14
J 0
(-6490 4185);
DISPLAY 0.680851 (-6490 4185);
PAINT MONO (-6490 4185);
FORCEPROP 0 LASTPIN (-6500 2525) $PN 107
J 0
(-6490 2535);
DISPLAY 0.680851 (-6490 2535);
PAINT MONO (-6490 2535);
FORCEPROP 0 LASTPIN (-6500 4225) $PN 16
J 0
(-6490 4235);
DISPLAY 0.680851 (-6490 4235);
PAINT MONO (-6490 4235);
FORCEPROP 0 LASTPIN (-6500 2575) $PN 109
J 0
(-6490 2585);
DISPLAY 0.680851 (-6490 2585);
PAINT MONO (-6490 2585);
FORCEPROP 0 LASTPIN (-6500 4275) $PN 159
J 0
(-6490 4285);
DISPLAY 0.680851 (-6490 4285);
PAINT MONO (-6490 4285);
FORCEPROP 0 LASTPIN (-6500 2625) $PN 252
J 0
(-6490 2635);
DISPLAY 0.680851 (-6490 2635);
PAINT MONO (-6490 2635);
FORCEPROP 0 LASTPIN (-6500 4325) $PN 161
J 0
(-6490 4335);
DISPLAY 0.680851 (-6490 4335);
PAINT MONO (-6490 4335);
FORCEPROP 0 LASTPIN (-6500 2675) $PN 254
J 0
(-6490 2685);
DISPLAY 0.680851 (-6490 2685);
PAINT MONO (-6490 2685);
FORCEPROP 0 LASTPIN (-6500 4375) $PN 18
J 0
(-6490 4385);
DISPLAY 0.680851 (-6490 4385);
PAINT MONO (-6490 4385);
FORCEPROP 0 LASTPIN (-6500 2725) $PN 111
J 0
(-6490 2735);
DISPLAY 0.680851 (-6490 2735);
PAINT MONO (-6490 2735);
FORCEPROP 0 LASTPIN (-6500 4425) $PN 20
J 0
(-6490 4435);
DISPLAY 0.680851 (-6490 4435);
PAINT MONO (-6490 4435);
FORCEPROP 0 LASTPIN (-6500 2775) $PN 113
J 0
(-6490 2785);
DISPLAY 0.680851 (-6490 2785);
PAINT MONO (-6490 2785);
FORCEPROP 0 LASTPIN (-6500 4475) $PN 163
J 0
(-6490 4485);
DISPLAY 0.680851 (-6490 4485);
PAINT MONO (-6490 4485);
FORCEPROP 0 LASTPIN (-6500 2825) $PN 256
J 0
(-6490 2835);
DISPLAY 0.680851 (-6490 2835);
PAINT MONO (-6490 2835);
FORCEPROP 0 LASTPIN (-6500 4525) $PN 165
J 0
(-6490 4535);
DISPLAY 0.680851 (-6490 4535);
PAINT MONO (-6490 4535);
FORCEPROP 0 LASTPIN (-6500 2875) $PN 258
J 0
(-6490 2885);
DISPLAY 0.680851 (-6490 2885);
PAINT MONO (-6490 2885);
FORCEPROP 0 LASTPIN (-6500 4575) $PN 25
J 0
(-6490 4585);
DISPLAY 0.680851 (-6490 4585);
PAINT MONO (-6490 4585);
FORCEPROP 0 LASTPIN (-6500 2925) $PN 118
J 0
(-6490 2935);
DISPLAY 0.680851 (-6490 2935);
PAINT MONO (-6490 2935);
FORCEPROP 0 LASTPIN (-6500 4625) $PN 27
J 0
(-6490 4635);
DISPLAY 0.680851 (-6490 4635);
PAINT MONO (-6490 4635);
FORCEPROP 0 LASTPIN (-6500 2975) $PN 120
J 0
(-6490 2985);
DISPLAY 0.680851 (-6490 2985);
PAINT MONO (-6490 2985);
FORCEPROP 0 LASTPIN (-6500 4675) $PN 170
J 0
(-6490 4685);
DISPLAY 0.680851 (-6490 4685);
PAINT MONO (-6490 4685);
FORCEPROP 0 LASTPIN (-6500 3025) $PN 263
J 0
(-6490 3035);
DISPLAY 0.680851 (-6490 3035);
PAINT MONO (-6490 3035);
FORCEPROP 0 LASTPIN (-6500 4725) $PN 172
J 0
(-6490 4735);
DISPLAY 0.680851 (-6490 4735);
PAINT MONO (-6490 4735);
FORCEPROP 0 LASTPIN (-6500 3075) $PN 265
J 0
(-6490 3085);
DISPLAY 0.680851 (-6490 3085);
PAINT MONO (-6490 3085);
FORCEPROP 0 LASTPIN (-6500 4775) $PN 29
J 0
(-6490 4785);
DISPLAY 0.680851 (-6490 4785);
PAINT MONO (-6490 4785);
FORCEPROP 0 LASTPIN (-6500 3125) $PN 122
J 0
(-6490 3135);
DISPLAY 0.680851 (-6490 3135);
PAINT MONO (-6490 3135);
FORCEPROP 0 LASTPIN (-6500 4825) $PN 31
J 0
(-6490 4835);
DISPLAY 0.680851 (-6490 4835);
PAINT MONO (-6490 4835);
FORCEPROP 0 LASTPIN (-6500 3175) $PN 124
J 0
(-6490 3185);
DISPLAY 0.680851 (-6490 3185);
PAINT MONO (-6490 3185);
FORCEPROP 0 LASTPIN (-6500 4875) $PN 174
J 0
(-6490 4885);
DISPLAY 0.680851 (-6490 4885);
PAINT MONO (-6490 4885);
FORCEPROP 0 LASTPIN (-6500 3225) $PN 267
J 0
(-6490 3235);
DISPLAY 0.680851 (-6490 3235);
PAINT MONO (-6490 3235);
FORCEPROP 0 LASTPIN (-6500 4925) $PN 176
J 0
(-6490 4935);
DISPLAY 0.680851 (-6490 4935);
PAINT MONO (-6490 4935);
FORCEPROP 0 LASTPIN (-6500 3275) $PN 269
J 0
(-6490 3285);
DISPLAY 0.680851 (-6490 3285);
PAINT MONO (-6490 3285);
FORCEPROP 0 LASTPIN (-6500 4975) $PN 36
J 0
(-6490 4985);
DISPLAY 0.680851 (-6490 4985);
PAINT MONO (-6490 4985);
FORCEPROP 0 LASTPIN (-6500 3325) $PN 129
J 0
(-6490 3335);
DISPLAY 0.680851 (-6490 3335);
PAINT MONO (-6490 3335);
FORCEPROP 0 LASTPIN (-6500 5025) $PN 38
J 0
(-6490 5035);
DISPLAY 0.680851 (-6490 5035);
PAINT MONO (-6490 5035);
FORCEPROP 0 LASTPIN (-6500 3375) $PN 131
J 0
(-6490 3385);
DISPLAY 0.680851 (-6490 3385);
PAINT MONO (-6490 3385);
FORCEPROP 0 LASTPIN (-6500 5075) $PN 181
J 0
(-6490 5085);
DISPLAY 0.680851 (-6490 5085);
PAINT MONO (-6490 5085);
FORCEPROP 0 LASTPIN (-6500 3425) $PN 274
J 0
(-6490 3435);
DISPLAY 0.680851 (-6490 3435);
PAINT MONO (-6490 3435);
FORCEPROP 0 LASTPIN (-6500 5125) $PN 183
J 0
(-6490 5135);
DISPLAY 0.680851 (-6490 5135);
PAINT MONO (-6490 5135);
FORCEPROP 0 LASTPIN (-6500 3475) $PN 276
J 0
(-6490 3485);
DISPLAY 0.680851 (-6490 3485);
PAINT MONO (-6490 3485);
FORCEPROP 0 LASTPIN (-6500 5175) $PN 40
J 0
(-6490 5185);
DISPLAY 0.680851 (-6490 5185);
PAINT MONO (-6490 5185);
FORCEPROP 0 LASTPIN (-6500 3525) $PN 133
J 0
(-6490 3535);
DISPLAY 0.680851 (-6490 3535);
PAINT MONO (-6490 3535);
FORCEPROP 0 LASTPIN (-6500 5225) $PN 42
J 0
(-6490 5235);
DISPLAY 0.680851 (-6490 5235);
PAINT MONO (-6490 5235);
FORCEPROP 0 LASTPIN (-6500 3575) $PN 135
J 0
(-6490 3585);
DISPLAY 0.680851 (-6490 3585);
PAINT MONO (-6490 3585);
FORCEPROP 0 LASTPIN (-6500 5275) $PN 185
J 0
(-6490 5285);
DISPLAY 0.680851 (-6490 5285);
PAINT MONO (-6490 5285);
FORCEPROP 0 LASTPIN (-6500 3625) $PN 278
J 0
(-6490 3635);
DISPLAY 0.680851 (-6490 3635);
PAINT MONO (-6490 3635);
FORCEPROP 0 LASTPIN (-6500 5325) $PN 187
J 0
(-6490 5335);
DISPLAY 0.680851 (-6490 5335);
PAINT MONO (-6490 5335);
FORCEPROP 0 LASTPIN (-6500 3675) $PN 280
J 0
(-6490 3685);
DISPLAY 0.680851 (-6490 3685);
PAINT MONO (-6490 3685);
FORCEPROP 0 LASTPIN (-6500 5375) $PN 47
J 0
(-6490 5385);
DISPLAY 0.680851 (-6490 5385);
PAINT MONO (-6490 5385);
FORCEPROP 0 LASTPIN (-6500 3725) $PN 140
J 0
(-6490 3735);
DISPLAY 0.680851 (-6490 3735);
PAINT MONO (-6490 3735);
FORCEPROP 0 LASTPIN (-6500 5425) $PN 49
J 0
(-6490 5435);
DISPLAY 0.680851 (-6490 5435);
PAINT MONO (-6490 5435);
FORCEPROP 0 LASTPIN (-6500 3775) $PN 142
J 0
(-6490 3785);
DISPLAY 0.680851 (-6490 3785);
PAINT MONO (-6490 3785);
FORCEPROP 0 LASTPIN (-6500 5475) $PN 192
J 0
(-6490 5485);
DISPLAY 0.680851 (-6490 5485);
PAINT MONO (-6490 5485);
FORCEPROP 0 LASTPIN (-6500 3825) $PN 285
J 0
(-6490 3835);
DISPLAY 0.680851 (-6490 3835);
PAINT MONO (-6490 3835);
FORCEPROP 0 LASTPIN (-6500 5525) $PN 194
J 0
(-6490 5535);
DISPLAY 0.680851 (-6490 5535);
PAINT MONO (-6490 5535);
FORCEPROP 0 LASTPIN (-6500 3875) $PN 287
J 0
(-6490 3885);
DISPLAY 0.680851 (-6490 3885);
PAINT MONO (-6490 3885);
FORCEPROP 0 LASTPIN (-7700 3025) $PN 148
J 2
(-7710 3035);
DISPLAY 0.680851 (-7710 3035);
PAINT MONO (-7710 3035);
FORCEPROP 0 LASTPIN (-7700 2925) $PN 4
J 2
(-7710 2935);
DISPLAY 0.680851 (-7710 2935);
PAINT MONO (-7710 2935);
FORCEPROP 0 LASTPIN (-7700 2975) $PN 5
J 2
(-7710 2985);
DISPLAY 0.680851 (-7710 2985);
PAINT MONO (-7710 2985);
FORCEPROP 0 LASTPIN (-7700 2125) $PN 86
J 2
(-7710 2135);
DISPLAY 0.680851 (-7710 2135);
PAINT MONO (-7710 2135);
FORCEPROP 0 LASTPIN (-7700 2075) $PN 87
J 2
(-7710 2085);
DISPLAY 0.680851 (-7710 2085);
PAINT MONO (-7710 2085);
FORCEPROP 0 LASTPIN (-7700 4725) $PN 74
J 2
(-7710 4735);
DISPLAY 0.680851 (-7710 4735);
PAINT MONO (-7710 4735);
FORCEPROP 0 LASTPIN (-7700 4675) $PN 227
J 2
(-7710 4685);
DISPLAY 0.680851 (-7710 4685);
PAINT MONO (-7710 4685);
FORCEPROP 0 LASTPIN (-7700 2675) $PN 147
J 2
(-7710 2685);
DISPLAY 0.680851 (-7710 2685);
PAINT MONO (-7710 2685);
FORCEPROP 0 LASTPIN (-7700 3225) $PN 207
J 2
(-7710 3235);
DISPLAY 0.680851 (-7710 3235);
PAINT MONO (-7710 3235);
FORCEPROP 0 LASTPIN (-7700 2275) $PN 2
J 2
(-7710 2285);
DISPLAY 0.680851 (-7710 2285);
PAINT MONO (-7710 2285);
FORCEPROP 0 LASTPIN (-7700 2325) $PN 144
J 2
(-7710 2335);
DISPLAY 0.680851 (-7710 2335);
PAINT MONO (-7710 2335);
FORCEPROP 0 LASTPIN (-7700 2375) $PN 149
J 2
(-7710 2385);
DISPLAY 0.680851 (-7710 2385);
PAINT MONO (-7710 2385);
FORCEPROP 0 LASTPIN (-7700 2425) $PN 150
J 2
(-7710 2435);
DISPLAY 0.680851 (-7710 2435);
PAINT MONO (-7710 2435);
FORCEPROP 0 LASTPIN (-7700 2475) $PN 220
J 2
(-7710 2485);
DISPLAY 0.680851 (-7710 2485);
PAINT MONO (-7710 2485);
FORCEPROP 0 LASTPIN (-7700 2525) $PN 231
J 2
(-7710 2535);
DISPLAY 0.680851 (-7710 2535);
PAINT MONO (-7710 2535);
FORCEPROP 0 LASTPIN (-7700 2575) $PN 232
J 2
(-7710 2585);
DISPLAY 0.680851 (-7710 2585);
PAINT MONO (-7710 2585);
FORCEPROP 0 LASTPIN (-7700 3075) $PN 3
J 2
(-7710 3085);
DISPLAY 0.680851 (-7710 3085);
PAINT MONO (-7710 3085);
FORCEPROP 2 LAST PART_TYPE SMLF
J 0
(-7550 5950);
DISPLAY 1.021277 (-7550 5950);
FORCEPROP 2 LAST VALUE SCONN288_DDR506112002KQ
J 0
(-7550 5900);
DISPLAY 0.489362 (-7550 5900);
PAINT SKYBLUE (-7550 5900);
FORCEPROP 1 LAST MATERIAL IO
J 0
(-7550 5700);
DISPLAY 0.468085 (-7550 5700);
PAINT SKYBLUE (-7550 5700);
FORCEPROP 1 LAST PART_NUMBER DFHST8FS479
J 0
(-7550 5775);
DISPLAY 0.468085 (-7550 5775);
PAINT SKYBLUE (-7550 5775);
FORCEPROP 1 LAST CDS_LMAN_SYM_OUTLINE -450,1900,450,-1850
J 0
(-7100 3775);
DISPLAY 0.468085 (-7100 3775);
PAINT GREEN (-7100 3775);
DISPLAY INVISIBLE (-7100 3775);
FORCEPROP 1 LAST PATH I350
J 0
(-7100 3775);
DISPLAY 0.723404 (-7100 3775);
PAINT GREEN (-7100 3775);
DISPLAY INVISIBLE (-7100 3775);
FORCEPROP 1 LAST NEEDS_NO_SIZE TRUE
J 0
(-7100 3775);
DISPLAY 0.723404 (-7100 3775);
PAINT GREEN (-7100 3775);
DISPLAY INVISIBLE (-7100 3775);
FORCEPROP 2 LAST CDS_LIB pure_quanta
J 0
(-7100 3775);
DISPLAY INVISIBLE (-7100 3775);
FORCEADD SCONN288_DDR506112002KQ..3
(-1225 3575);
FORCEPROP 1 LAST LOCATION J15
J 0
(-1675 5550);
DISPLAY 0.574468 (-1675 5550);
PAINT SKYBLUE (-1675 5550);
FORCEPROP 0 LAST $SEC 3
J 0
(-1675 5700);
DISPLAY 0.680851 (-1675 5700);
PAINT MONO (-1675 5700);
DISPLAY INVISIBLE (-1675 5700);
FORCEPROP 2 LAST CDS_SEC 3
J 0
(-1675 5700);
DISPLAY 1.021277 (-1675 5700);
DISPLAY INVISIBLE (-1675 5700);
FORCEPROP 0 LASTPIN (-625 1975) $PN G1
J 0
(-615 1985);
DISPLAY 0.680851 (-615 1985);
PAINT MONO (-615 1985);
FORCEPROP 0 LASTPIN (-625 1925) $PN G2
J 0
(-615 1935);
DISPLAY 0.680851 (-615 1935);
PAINT MONO (-615 1935);
FORCEPROP 0 LASTPIN (-625 1875) $PN G3
J 0
(-615 1885);
DISPLAY 0.680851 (-615 1885);
PAINT MONO (-615 1885);
FORCEPROP 0 LASTPIN (-1825 5125) $PN 1
J 2
(-1835 5135);
DISPLAY 0.680851 (-1835 5135);
PAINT MONO (-1835 5135);
FORCEPROP 0 LASTPIN (-1825 5175) $PN 145
J 2
(-1835 5185);
DISPLAY 0.680851 (-1835 5185);
PAINT MONO (-1835 5185);
FORCEPROP 0 LASTPIN (-1825 5225) $PN 146
J 2
(-1835 5235);
DISPLAY 0.680851 (-1835 5235);
PAINT MONO (-1835 5235);
FORCEPROP 0 LASTPIN (-625 2075) $PN 6
J 0
(-615 2085);
DISPLAY 0.680851 (-615 2085);
PAINT MONO (-615 2085);
FORCEPROP 0 LASTPIN (-625 2125) $PN 8
J 0
(-615 2135);
DISPLAY 0.680851 (-615 2135);
PAINT MONO (-615 2135);
FORCEPROP 0 LASTPIN (-625 2175) $PN 10
J 0
(-615 2185);
DISPLAY 0.680851 (-615 2185);
PAINT MONO (-615 2185);
FORCEPROP 0 LASTPIN (-625 2225) $PN 13
J 0
(-615 2235);
DISPLAY 0.680851 (-615 2235);
PAINT MONO (-615 2235);
FORCEPROP 0 LASTPIN (-625 2275) $PN 15
J 0
(-615 2285);
DISPLAY 0.680851 (-615 2285);
PAINT MONO (-615 2285);
FORCEPROP 0 LASTPIN (-625 2325) $PN 17
J 0
(-615 2335);
DISPLAY 0.680851 (-615 2335);
PAINT MONO (-615 2335);
FORCEPROP 0 LASTPIN (-625 2375) $PN 19
J 0
(-615 2385);
DISPLAY 0.680851 (-615 2385);
PAINT MONO (-615 2385);
FORCEPROP 0 LASTPIN (-625 2425) $PN 21
J 0
(-615 2435);
DISPLAY 0.680851 (-615 2435);
PAINT MONO (-615 2435);
FORCEPROP 0 LASTPIN (-625 2475) $PN 24
J 0
(-615 2485);
DISPLAY 0.680851 (-615 2485);
PAINT MONO (-615 2485);
FORCEPROP 0 LASTPIN (-625 2525) $PN 26
J 0
(-615 2535);
DISPLAY 0.680851 (-615 2535);
PAINT MONO (-615 2535);
FORCEPROP 0 LASTPIN (-625 2575) $PN 28
J 0
(-615 2585);
DISPLAY 0.680851 (-615 2585);
PAINT MONO (-615 2585);
FORCEPROP 0 LASTPIN (-625 2625) $PN 30
J 0
(-615 2635);
DISPLAY 0.680851 (-615 2635);
PAINT MONO (-615 2635);
FORCEPROP 0 LASTPIN (-625 2675) $PN 32
J 0
(-615 2685);
DISPLAY 0.680851 (-615 2685);
PAINT MONO (-615 2685);
FORCEPROP 0 LASTPIN (-625 2725) $PN 35
J 0
(-615 2735);
DISPLAY 0.680851 (-615 2735);
PAINT MONO (-615 2735);
FORCEPROP 0 LASTPIN (-625 2775) $PN 37
J 0
(-615 2785);
DISPLAY 0.680851 (-615 2785);
PAINT MONO (-615 2785);
FORCEPROP 0 LASTPIN (-625 2825) $PN 39
J 0
(-615 2835);
DISPLAY 0.680851 (-615 2835);
PAINT MONO (-615 2835);
FORCEPROP 0 LASTPIN (-625 2875) $PN 41
J 0
(-615 2885);
DISPLAY 0.680851 (-615 2885);
PAINT MONO (-615 2885);
FORCEPROP 0 LASTPIN (-625 2925) $PN 43
J 0
(-615 2935);
DISPLAY 0.680851 (-615 2935);
PAINT MONO (-615 2935);
FORCEPROP 0 LASTPIN (-625 2975) $PN 46
J 0
(-615 2985);
DISPLAY 0.680851 (-615 2985);
PAINT MONO (-615 2985);
FORCEPROP 0 LASTPIN (-625 3025) $PN 48
J 0
(-615 3035);
DISPLAY 0.680851 (-615 3035);
PAINT MONO (-615 3035);
FORCEPROP 0 LASTPIN (-625 3075) $PN 50
J 0
(-615 3085);
DISPLAY 0.680851 (-615 3085);
PAINT MONO (-615 3085);
FORCEPROP 0 LASTPIN (-625 3125) $PN 52
J 0
(-615 3135);
DISPLAY 0.680851 (-615 3135);
PAINT MONO (-615 3135);
FORCEPROP 0 LASTPIN (-625 3175) $PN 54
J 0
(-615 3185);
DISPLAY 0.680851 (-615 3185);
PAINT MONO (-615 3185);
FORCEPROP 0 LASTPIN (-625 3225) $PN 57
J 0
(-615 3235);
DISPLAY 0.680851 (-615 3235);
PAINT MONO (-615 3235);
FORCEPROP 0 LASTPIN (-625 3275) $PN 59
J 0
(-615 3285);
DISPLAY 0.680851 (-615 3285);
PAINT MONO (-615 3285);
FORCEPROP 0 LASTPIN (-625 3325) $PN 61
J 0
(-615 3335);
DISPLAY 0.680851 (-615 3335);
PAINT MONO (-615 3335);
FORCEPROP 0 LASTPIN (-625 3375) $PN 63
J 0
(-615 3385);
DISPLAY 0.680851 (-615 3385);
PAINT MONO (-615 3385);
FORCEPROP 0 LASTPIN (-625 3425) $PN 65
J 0
(-615 3435);
DISPLAY 0.680851 (-615 3435);
PAINT MONO (-615 3435);
FORCEPROP 0 LASTPIN (-625 3475) $PN 67
J 0
(-615 3485);
DISPLAY 0.680851 (-615 3485);
PAINT MONO (-615 3485);
FORCEPROP 0 LASTPIN (-625 3525) $PN 69
J 0
(-615 3535);
DISPLAY 0.680851 (-615 3535);
PAINT MONO (-615 3535);
FORCEPROP 0 LASTPIN (-625 3575) $PN 71
J 0
(-615 3585);
DISPLAY 0.680851 (-615 3585);
PAINT MONO (-615 3585);
FORCEPROP 0 LASTPIN (-625 3625) $PN 73
J 0
(-615 3635);
DISPLAY 0.680851 (-615 3635);
PAINT MONO (-615 3635);
FORCEPROP 0 LASTPIN (-625 3675) $PN 75
J 0
(-615 3685);
DISPLAY 0.680851 (-615 3685);
PAINT MONO (-615 3685);
FORCEPROP 0 LASTPIN (-625 3725) $PN 77
J 0
(-615 3735);
DISPLAY 0.680851 (-615 3735);
PAINT MONO (-615 3735);
FORCEPROP 0 LASTPIN (-625 3775) $PN 79
J 0
(-615 3785);
DISPLAY 0.680851 (-615 3785);
PAINT MONO (-615 3785);
FORCEPROP 0 LASTPIN (-625 3825) $PN 81
J 0
(-615 3835);
DISPLAY 0.680851 (-615 3835);
PAINT MONO (-615 3835);
FORCEPROP 0 LASTPIN (-625 3875) $PN 83
J 0
(-615 3885);
DISPLAY 0.680851 (-615 3885);
PAINT MONO (-615 3885);
FORCEPROP 0 LASTPIN (-625 3925) $PN 85
J 0
(-615 3935);
DISPLAY 0.680851 (-615 3935);
PAINT MONO (-615 3935);
FORCEPROP 0 LASTPIN (-625 3975) $PN 88
J 0
(-615 3985);
DISPLAY 0.680851 (-615 3985);
PAINT MONO (-615 3985);
FORCEPROP 0 LASTPIN (-625 4025) $PN 90
J 0
(-615 4035);
DISPLAY 0.680851 (-615 4035);
PAINT MONO (-615 4035);
FORCEPROP 0 LASTPIN (-625 4075) $PN 92
J 0
(-615 4085);
DISPLAY 0.680851 (-615 4085);
PAINT MONO (-615 4085);
FORCEPROP 0 LASTPIN (-625 4125) $PN 95
J 0
(-615 4135);
DISPLAY 0.680851 (-615 4135);
PAINT MONO (-615 4135);
FORCEPROP 0 LASTPIN (-625 4175) $PN 97
J 0
(-615 4185);
DISPLAY 0.680851 (-615 4185);
PAINT MONO (-615 4185);
FORCEPROP 0 LASTPIN (-625 4225) $PN 99
J 0
(-615 4235);
DISPLAY 0.680851 (-615 4235);
PAINT MONO (-615 4235);
FORCEPROP 0 LASTPIN (-625 4275) $PN 101
J 0
(-615 4285);
DISPLAY 0.680851 (-615 4285);
PAINT MONO (-615 4285);
FORCEPROP 0 LASTPIN (-625 4325) $PN 103
J 0
(-615 4335);
DISPLAY 0.680851 (-615 4335);
PAINT MONO (-615 4335);
FORCEPROP 0 LASTPIN (-625 4375) $PN 106
J 0
(-615 4385);
DISPLAY 0.680851 (-615 4385);
PAINT MONO (-615 4385);
FORCEPROP 0 LASTPIN (-625 4425) $PN 108
J 0
(-615 4435);
DISPLAY 0.680851 (-615 4435);
PAINT MONO (-615 4435);
FORCEPROP 0 LASTPIN (-625 4475) $PN 110
J 0
(-615 4485);
DISPLAY 0.680851 (-615 4485);
PAINT MONO (-615 4485);
FORCEPROP 0 LASTPIN (-625 4525) $PN 112
J 0
(-615 4535);
DISPLAY 0.680851 (-615 4535);
PAINT MONO (-615 4535);
FORCEPROP 0 LASTPIN (-625 4575) $PN 114
J 0
(-615 4585);
DISPLAY 0.680851 (-615 4585);
PAINT MONO (-615 4585);
FORCEPROP 0 LASTPIN (-625 4625) $PN 117
J 0
(-615 4635);
DISPLAY 0.680851 (-615 4635);
PAINT MONO (-615 4635);
FORCEPROP 0 LASTPIN (-625 4675) $PN 119
J 0
(-615 4685);
DISPLAY 0.680851 (-615 4685);
PAINT MONO (-615 4685);
FORCEPROP 0 LASTPIN (-625 4725) $PN 121
J 0
(-615 4735);
DISPLAY 0.680851 (-615 4735);
PAINT MONO (-615 4735);
FORCEPROP 0 LASTPIN (-625 4775) $PN 123
J 0
(-615 4785);
DISPLAY 0.680851 (-615 4785);
PAINT MONO (-615 4785);
FORCEPROP 0 LASTPIN (-625 4825) $PN 125
J 0
(-615 4835);
DISPLAY 0.680851 (-615 4835);
PAINT MONO (-615 4835);
FORCEPROP 0 LASTPIN (-625 4875) $PN 128
J 0
(-615 4885);
DISPLAY 0.680851 (-615 4885);
PAINT MONO (-615 4885);
FORCEPROP 0 LASTPIN (-625 4925) $PN 130
J 0
(-615 4935);
DISPLAY 0.680851 (-615 4935);
PAINT MONO (-615 4935);
FORCEPROP 0 LASTPIN (-625 4975) $PN 132
J 0
(-615 4985);
DISPLAY 0.680851 (-615 4985);
PAINT MONO (-615 4985);
FORCEPROP 0 LASTPIN (-625 5025) $PN 134
J 0
(-615 5035);
DISPLAY 0.680851 (-615 5035);
PAINT MONO (-615 5035);
FORCEPROP 0 LASTPIN (-625 5075) $PN 136
J 0
(-615 5085);
DISPLAY 0.680851 (-615 5085);
PAINT MONO (-615 5085);
FORCEPROP 0 LASTPIN (-625 5125) $PN 139
J 0
(-615 5135);
DISPLAY 0.680851 (-615 5135);
PAINT MONO (-615 5135);
FORCEPROP 0 LASTPIN (-625 5175) $PN 141
J 0
(-615 5185);
DISPLAY 0.680851 (-615 5185);
PAINT MONO (-615 5185);
FORCEPROP 0 LASTPIN (-625 5225) $PN 143
J 0
(-615 5235);
DISPLAY 0.680851 (-615 5235);
PAINT MONO (-615 5235);
FORCEPROP 0 LASTPIN (-1825 1975) $PN 151
J 2
(-1835 1985);
DISPLAY 0.680851 (-1835 1985);
PAINT MONO (-1835 1985);
FORCEPROP 0 LASTPIN (-1825 2025) $PN 153
J 2
(-1835 2035);
DISPLAY 0.680851 (-1835 2035);
PAINT MONO (-1835 2035);
FORCEPROP 0 LASTPIN (-1825 2075) $PN 155
J 2
(-1835 2085);
DISPLAY 0.680851 (-1835 2085);
PAINT MONO (-1835 2085);
FORCEPROP 0 LASTPIN (-1825 2125) $PN 158
J 2
(-1835 2135);
DISPLAY 0.680851 (-1835 2135);
PAINT MONO (-1835 2135);
FORCEPROP 0 LASTPIN (-1825 2175) $PN 160
J 2
(-1835 2185);
DISPLAY 0.680851 (-1835 2185);
PAINT MONO (-1835 2185);
FORCEPROP 0 LASTPIN (-1825 2225) $PN 162
J 2
(-1835 2235);
DISPLAY 0.680851 (-1835 2235);
PAINT MONO (-1835 2235);
FORCEPROP 0 LASTPIN (-1825 2275) $PN 164
J 2
(-1835 2285);
DISPLAY 0.680851 (-1835 2285);
PAINT MONO (-1835 2285);
FORCEPROP 0 LASTPIN (-1825 2325) $PN 166
J 2
(-1835 2335);
DISPLAY 0.680851 (-1835 2335);
PAINT MONO (-1835 2335);
FORCEPROP 0 LASTPIN (-1825 2375) $PN 169
J 2
(-1835 2385);
DISPLAY 0.680851 (-1835 2385);
PAINT MONO (-1835 2385);
FORCEPROP 0 LASTPIN (-1825 2425) $PN 171
J 2
(-1835 2435);
DISPLAY 0.680851 (-1835 2435);
PAINT MONO (-1835 2435);
FORCEPROP 0 LASTPIN (-1825 2475) $PN 173
J 2
(-1835 2485);
DISPLAY 0.680851 (-1835 2485);
PAINT MONO (-1835 2485);
FORCEPROP 0 LASTPIN (-1825 2525) $PN 175
J 2
(-1835 2535);
DISPLAY 0.680851 (-1835 2535);
PAINT MONO (-1835 2535);
FORCEPROP 0 LASTPIN (-1825 2575) $PN 177
J 2
(-1835 2585);
DISPLAY 0.680851 (-1835 2585);
PAINT MONO (-1835 2585);
FORCEPROP 0 LASTPIN (-1825 2625) $PN 180
J 2
(-1835 2635);
DISPLAY 0.680851 (-1835 2635);
PAINT MONO (-1835 2635);
FORCEPROP 0 LASTPIN (-1825 2675) $PN 182
J 2
(-1835 2685);
DISPLAY 0.680851 (-1835 2685);
PAINT MONO (-1835 2685);
FORCEPROP 0 LASTPIN (-1825 2725) $PN 184
J 2
(-1835 2735);
DISPLAY 0.680851 (-1835 2735);
PAINT MONO (-1835 2735);
FORCEPROP 0 LASTPIN (-1825 2775) $PN 186
J 2
(-1835 2785);
DISPLAY 0.680851 (-1835 2785);
PAINT MONO (-1835 2785);
FORCEPROP 0 LASTPIN (-1825 2825) $PN 188
J 2
(-1835 2835);
DISPLAY 0.680851 (-1835 2835);
PAINT MONO (-1835 2835);
FORCEPROP 0 LASTPIN (-1825 2875) $PN 191
J 2
(-1835 2885);
DISPLAY 0.680851 (-1835 2885);
PAINT MONO (-1835 2885);
FORCEPROP 0 LASTPIN (-1825 2925) $PN 193
J 2
(-1835 2935);
DISPLAY 0.680851 (-1835 2935);
PAINT MONO (-1835 2935);
FORCEPROP 0 LASTPIN (-1825 2975) $PN 195
J 2
(-1835 2985);
DISPLAY 0.680851 (-1835 2985);
PAINT MONO (-1835 2985);
FORCEPROP 0 LASTPIN (-1825 3025) $PN 197
J 2
(-1835 3035);
DISPLAY 0.680851 (-1835 3035);
PAINT MONO (-1835 3035);
FORCEPROP 0 LASTPIN (-1825 3075) $PN 199
J 2
(-1835 3085);
DISPLAY 0.680851 (-1835 3085);
PAINT MONO (-1835 3085);
FORCEPROP 0 LASTPIN (-1825 3125) $PN 202
J 2
(-1835 3135);
DISPLAY 0.680851 (-1835 3135);
PAINT MONO (-1835 3135);
FORCEPROP 0 LASTPIN (-1825 3175) $PN 204
J 2
(-1835 3185);
DISPLAY 0.680851 (-1835 3185);
PAINT MONO (-1835 3185);
FORCEPROP 0 LASTPIN (-1825 3225) $PN 206
J 2
(-1835 3235);
DISPLAY 0.680851 (-1835 3235);
PAINT MONO (-1835 3235);
FORCEPROP 0 LASTPIN (-1825 3275) $PN 208
J 2
(-1835 3285);
DISPLAY 0.680851 (-1835 3285);
PAINT MONO (-1835 3285);
FORCEPROP 0 LASTPIN (-1825 3325) $PN 210
J 2
(-1835 3335);
DISPLAY 0.680851 (-1835 3335);
PAINT MONO (-1835 3335);
FORCEPROP 0 LASTPIN (-1825 3375) $PN 212
J 2
(-1835 3385);
DISPLAY 0.680851 (-1835 3385);
PAINT MONO (-1835 3385);
FORCEPROP 0 LASTPIN (-1825 3425) $PN 214
J 2
(-1835 3435);
DISPLAY 0.680851 (-1835 3435);
PAINT MONO (-1835 3435);
FORCEPROP 0 LASTPIN (-1825 3475) $PN 216
J 2
(-1835 3485);
DISPLAY 0.680851 (-1835 3485);
PAINT MONO (-1835 3485);
FORCEPROP 0 LASTPIN (-1825 3525) $PN 219
J 2
(-1835 3535);
DISPLAY 0.680851 (-1835 3535);
PAINT MONO (-1835 3535);
FORCEPROP 0 LASTPIN (-1825 3575) $PN 222
J 2
(-1835 3585);
DISPLAY 0.680851 (-1835 3585);
PAINT MONO (-1835 3585);
FORCEPROP 0 LASTPIN (-1825 3625) $PN 224
J 2
(-1835 3635);
DISPLAY 0.680851 (-1835 3635);
PAINT MONO (-1835 3635);
FORCEPROP 0 LASTPIN (-1825 3675) $PN 226
J 2
(-1835 3685);
DISPLAY 0.680851 (-1835 3685);
PAINT MONO (-1835 3685);
FORCEPROP 0 LASTPIN (-1825 3725) $PN 228
J 2
(-1835 3735);
DISPLAY 0.680851 (-1835 3735);
PAINT MONO (-1835 3735);
FORCEPROP 0 LASTPIN (-1825 3775) $PN 230
J 2
(-1835 3785);
DISPLAY 0.680851 (-1835 3785);
PAINT MONO (-1835 3785);
FORCEPROP 0 LASTPIN (-1825 3825) $PN 233
J 2
(-1835 3835);
DISPLAY 0.680851 (-1835 3835);
PAINT MONO (-1835 3835);
FORCEPROP 0 LASTPIN (-1825 3875) $PN 235
J 2
(-1835 3885);
DISPLAY 0.680851 (-1835 3885);
PAINT MONO (-1835 3885);
FORCEPROP 0 LASTPIN (-1825 3925) $PN 237
J 2
(-1835 3935);
DISPLAY 0.680851 (-1835 3935);
PAINT MONO (-1835 3935);
FORCEPROP 0 LASTPIN (-1825 3975) $PN 240
J 2
(-1835 3985);
DISPLAY 0.680851 (-1835 3985);
PAINT MONO (-1835 3985);
FORCEPROP 0 LASTPIN (-1825 4025) $PN 242
J 2
(-1835 4035);
DISPLAY 0.680851 (-1835 4035);
PAINT MONO (-1835 4035);
FORCEPROP 0 LASTPIN (-1825 4075) $PN 244
J 2
(-1835 4085);
DISPLAY 0.680851 (-1835 4085);
PAINT MONO (-1835 4085);
FORCEPROP 0 LASTPIN (-1825 4125) $PN 246
J 2
(-1835 4135);
DISPLAY 0.680851 (-1835 4135);
PAINT MONO (-1835 4135);
FORCEPROP 0 LASTPIN (-1825 4175) $PN 248
J 2
(-1835 4185);
DISPLAY 0.680851 (-1835 4185);
PAINT MONO (-1835 4185);
FORCEPROP 0 LASTPIN (-1825 4225) $PN 251
J 2
(-1835 4235);
DISPLAY 0.680851 (-1835 4235);
PAINT MONO (-1835 4235);
FORCEPROP 0 LASTPIN (-1825 4275) $PN 253
J 2
(-1835 4285);
DISPLAY 0.680851 (-1835 4285);
PAINT MONO (-1835 4285);
FORCEPROP 0 LASTPIN (-1825 4325) $PN 255
J 2
(-1835 4335);
DISPLAY 0.680851 (-1835 4335);
PAINT MONO (-1835 4335);
FORCEPROP 0 LASTPIN (-1825 4375) $PN 257
J 2
(-1835 4385);
DISPLAY 0.680851 (-1835 4385);
PAINT MONO (-1835 4385);
FORCEPROP 0 LASTPIN (-1825 4425) $PN 259
J 2
(-1835 4435);
DISPLAY 0.680851 (-1835 4435);
PAINT MONO (-1835 4435);
FORCEPROP 0 LASTPIN (-1825 4475) $PN 262
J 2
(-1835 4485);
DISPLAY 0.680851 (-1835 4485);
PAINT MONO (-1835 4485);
FORCEPROP 0 LASTPIN (-1825 4525) $PN 264
J 2
(-1835 4535);
DISPLAY 0.680851 (-1835 4535);
PAINT MONO (-1835 4535);
FORCEPROP 0 LASTPIN (-1825 4575) $PN 266
J 2
(-1835 4585);
DISPLAY 0.680851 (-1835 4585);
PAINT MONO (-1835 4585);
FORCEPROP 0 LASTPIN (-1825 4625) $PN 268
J 2
(-1835 4635);
DISPLAY 0.680851 (-1835 4635);
PAINT MONO (-1835 4635);
FORCEPROP 0 LASTPIN (-1825 4675) $PN 270
J 2
(-1835 4685);
DISPLAY 0.680851 (-1835 4685);
PAINT MONO (-1835 4685);
FORCEPROP 0 LASTPIN (-1825 4725) $PN 273
J 2
(-1835 4735);
DISPLAY 0.680851 (-1835 4735);
PAINT MONO (-1835 4735);
FORCEPROP 0 LASTPIN (-1825 4775) $PN 275
J 2
(-1835 4785);
DISPLAY 0.680851 (-1835 4785);
PAINT MONO (-1835 4785);
FORCEPROP 0 LASTPIN (-1825 4825) $PN 277
J 2
(-1835 4835);
DISPLAY 0.680851 (-1835 4835);
PAINT MONO (-1835 4835);
FORCEPROP 0 LASTPIN (-1825 4875) $PN 279
J 2
(-1835 4885);
DISPLAY 0.680851 (-1835 4885);
PAINT MONO (-1835 4885);
FORCEPROP 0 LASTPIN (-1825 4925) $PN 281
J 2
(-1835 4935);
DISPLAY 0.680851 (-1835 4935);
PAINT MONO (-1835 4935);
FORCEPROP 0 LASTPIN (-1825 4975) $PN 284
J 2
(-1835 4985);
DISPLAY 0.680851 (-1835 4985);
PAINT MONO (-1835 4985);
FORCEPROP 0 LASTPIN (-1825 5025) $PN 286
J 2
(-1835 5035);
DISPLAY 0.680851 (-1835 5035);
PAINT MONO (-1835 5035);
FORCEPROP 0 LASTPIN (-1825 5075) $PN 288
J 2
(-1835 5085);
DISPLAY 0.680851 (-1835 5085);
PAINT MONO (-1835 5085);
FORCEPROP 2 LAST VALUE SCONN288_DDR506112002KQ
J 0
(-1675 5600);
DISPLAY 0.489362 (-1675 5600);
PAINT SKYBLUE (-1675 5600);
FORCEPROP 1 LAST MATERIAL IO
J 0
(-1675 5400);
DISPLAY 0.468085 (-1675 5400);
PAINT SKYBLUE (-1675 5400);
FORCEPROP 2 LAST PART_TYPE SMLF
J 0
(-1675 5650);
DISPLAY 1.021277 (-1675 5650);
FORCEPROP 1 LAST PART_NUMBER DFHST8FS479
J 0
(-1675 5475);
DISPLAY 0.468085 (-1675 5475);
PAINT SKYBLUE (-1675 5475);
FORCEPROP 1 LAST CDS_LMAN_SYM_OUTLINE -450,1800,450,-1750
J 0
(-1225 3575);
DISPLAY 0.468085 (-1225 3575);
PAINT GREEN (-1225 3575);
DISPLAY INVISIBLE (-1225 3575);
FORCEPROP 1 LAST PATH I352
J 0
(-1225 3575);
DISPLAY 0.723404 (-1225 3575);
PAINT GREEN (-1225 3575);
DISPLAY INVISIBLE (-1225 3575);
FORCEPROP 1 LAST NEEDS_NO_SIZE TRUE
J 0
(-1225 3575);
DISPLAY 0.723404 (-1225 3575);
PAINT GREEN (-1225 3575);
DISPLAY INVISIBLE (-1225 3575);
FORCEPROP 2 LAST CDS_LIB pure_quanta
J 0
(-1225 3575);
DISPLAY INVISIBLE (-1225 3575);
FORCEADD OFFPAGE..5
(-8525 3175);
FORCEPROP 2 LAST $XR0 11 
J 0
(-8779 3175);
DISPLAY 0.638298 (-8779 3175);
PAINT MONO (-8779 3175);
FORCEPROP 2 LAST PATH I353
J 0
(-8475 3250);
DISPLAY 1.021277 (-8475 3250);
DISPLAY INVISIBLE (-8475 3250);
FORCEPROP 1 LAST COMMENT_BODY TRUE
J 0
(-8425 3100);
DISPLAY 0.872340 (-8425 3100);
PAINT GREEN (-8425 3100);
DISPLAY INVISIBLE (-8425 3100);
FORCEPROP 1 LAST OFFPAGE TRUE
J 0
(-8200 3050);
DISPLAY 0.872340 (-8200 3050);
PAINT GREEN (-8200 3050);
DISPLAY INVISIBLE (-8200 3050);
FORCEPROP 2 LAST CDS_LIB mstr_standard
J 0
(-8525 3175);
DISPLAY INVISIBLE (-8525 3175);
FORCEADD OFFPAGE..1
(-8550 2825);
FORCEPROP 2 LAST $XR5 90 
J 0
(-9252 2825);
DISPLAY 0.638298 (-9252 2825);
PAINT MONO (-9252 2825);
FORCEPROP 2 LAST $XR4 89 
J 0
(-9162 2825);
DISPLAY 0.638298 (-9162 2825);
PAINT MONO (-9162 2825);
FORCEPROP 2 LAST $XR3 88 
J 0
(-9072 2825);
DISPLAY 0.638298 (-9072 2825);
PAINT MONO (-9072 2825);
FORCEPROP 2 LAST $XR2 87 
J 0
(-8982 2825);
DISPLAY 0.638298 (-8982 2825);
PAINT MONO (-8982 2825);
FORCEPROP 2 LAST $XR1 85 
J 0
(-8892 2825);
DISPLAY 0.638298 (-8892 2825);
PAINT MONO (-8892 2825);
FORCEPROP 2 LAST $XR0 136 
J 0
(-8802 2825);
DISPLAY 0.638298 (-8802 2825);
PAINT MONO (-8802 2825);
FORCEPROP 2 LAST CDS_LIB mstr_standard
J 0
(-8550 2825);
DISPLAY 0.808511 (-8550 2825);
DISPLAY INVISIBLE (-8550 2825);
FORCEPROP 1 LAST OFFPAGE TRUE
J 0
(-8225 2700);
DISPLAY 0.872340 (-8225 2700);
PAINT GREEN (-8225 2700);
DISPLAY INVISIBLE (-8225 2700);
FORCEPROP 1 LAST COMMENT_BODY TRUE
J 0
(-8425 2725);
DISPLAY 0.872340 (-8425 2725);
PAINT GREEN (-8425 2725);
DISPLAY INVISIBLE (-8425 2725);
FORCEPROP 2 LAST PATH I354
J 0
(-8825 2875);
DISPLAY 1.021277 (-8825 2875);
DISPLAY INVISIBLE (-8825 2875);
FORCEADD OFFPAGE..6
(-8550 2975);
FORCEPROP 2 LAST $XR5 136 
J 0
(-9279 2975);
DISPLAY 0.638298 (-9279 2975);
PAINT MONO (-9279 2975);
FORCEPROP 2 LAST $XR4 90 
J 0
(-9159 2975);
DISPLAY 0.638298 (-9159 2975);
PAINT MONO (-9159 2975);
FORCEPROP 2 LAST $XR3 89 
J 0
(-9069 2975);
DISPLAY 0.638298 (-9069 2975);
PAINT MONO (-9069 2975);
FORCEPROP 2 LAST $XR2 88 
J 0
(-8979 2975);
DISPLAY 0.638298 (-8979 2975);
PAINT MONO (-8979 2975);
FORCEPROP 2 LAST $XR1 87 
J 0
(-8889 2975);
DISPLAY 0.638298 (-8889 2975);
PAINT MONO (-8889 2975);
FORCEPROP 2 LAST $XR0 85 
J 0
(-8799 2975);
DISPLAY 0.638298 (-8799 2975);
PAINT MONO (-8799 2975);
FORCEPROP 2 LAST PATH I355
J 0
(-8825 3025);
DISPLAY 1.021277 (-8825 3025);
DISPLAY INVISIBLE (-8825 3025);
FORCEPROP 1 LAST COMMENT_BODY TRUE
J 0
(-8450 2900);
DISPLAY 0.872340 (-8450 2900);
PAINT GREEN (-8450 2900);
DISPLAY INVISIBLE (-8450 2900);
FORCEPROP 1 LAST OFFPAGE TRUE
J 0
(-8225 2850);
DISPLAY 0.872340 (-8225 2850);
PAINT GREEN (-8225 2850);
DISPLAY INVISIBLE (-8225 2850);
FORCEPROP 2 LAST CDS_LIB mstr_standard
J 0
(-8550 2975);
DISPLAY 0.808511 (-8550 2975);
DISPLAY INVISIBLE (-8550 2975);
FORCEADD GND..1
(-9050 3100);
FORCEPROP 3 LASTPIN (-9050 3150) SIG_NAME GND\g
J 0
(-9040 3160);
DISPLAY 0.659574 (-9040 3160);
PAINT MONO (-9040 3160);
DISPLAY INVISIBLE (-9040 3160);
FORCEPROP 2 LAST BOM_COST MEM
J 0
(-9025 3225);
DISPLAY 0.659574 (-9025 3225);
DISPLAY INVISIBLE (-9025 3225);
FORCEPROP 1 LAST SIZE 1B
J 0
(-8975 3050);
DISPLAY 0.723404 (-8975 3050);
PAINT GREEN (-8975 3050);
DISPLAY INVISIBLE (-8975 3050);
FORCEPROP 2 LAST CDS_LIB mstr_symbols
J 0
(-9050 3100);
DISPLAY 0.808511 (-9050 3100);
DISPLAY INVISIBLE (-9050 3100);
FORCEPROP 1 LAST BODY_TYPE PLUMBING
J 0
(-9095 3057);
DISPLAY 0.276596 (-9095 3057);
PAINT GREEN (-9095 3057);
DISPLAY INVISIBLE (-9095 3057);
FORCEPROP 1 LAST PATH I361
J 0
(-8975 3100);
DISPLAY 0.872340 (-8975 3100);
PAINT AQUA (-8975 3100);
DISPLAY INVISIBLE (-8975 3100);
FORCEPROP 1 LAST VOLTAGE 0
J 0
(-9070 3195);
DISPLAY 0.829787 (-9070 3195);
PAINT SKYBLUE (-9070 3195);
DISPLAY INVISIBLE (-9070 3195);
FORCEPROP 2 LAST ROOM MEM_EFGH_DECOUPLING_CAPS
J 0
(-9025 3175);
DISPLAY 0.659574 (-9025 3175);
PAINT RED (-9025 3175);
DISPLAY INVISIBLE (-9025 3175);
FORCEPROP 1 LAST HDL_POWER GND
J 0
(-9050 3250);
DISPLAY 0.723404 (-9050 3250);
PAINT GREEN (-9050 3250);
DISPLAY INVISIBLE (-9050 3250);
FORCEADD Q_CAP..1
R 2
(-9050 3325);
FORCEPROP 1 LAST LOCATION C92
J 2
(-9100 3425);
DISPLAY 0.489362 (-9100 3425);
PAINT SKYBLUE (-9100 3425);
FORCEPROP 0 LAST $SEC 1
J 0
(-9100 3475);
DISPLAY 0.680851 (-9100 3475);
PAINT MONO (-9100 3475);
DISPLAY INVISIBLE (-9100 3475);
FORCEPROP 0 LAST CDS_SEC 1
J 0
(-9100 3475);
DISPLAY 1.021277 (-9100 3475);
DISPLAY INVISIBLE (-9100 3475);
FORCEPROP 1 LASTPIN (-9050 3425) $PN 1
J 2
(-9060 3405);
DISPLAY 0.489362 (-9060 3405);
PAINT MONO (-9060 3405);
FORCEPROP 1 LASTPIN (-9050 3225) $PN 2
J 2
(-9060 3205);
DISPLAY 0.489362 (-9060 3205);
PAINT MONO (-9060 3205);
FORCEPROP 1 LAST TOLERANCE 10%
J 2
(-9100 3275);
DISPLAY 0.489362 (-9100 3275);
PAINT SKYBLUE (-9100 3275);
FORCEPROP 1 LAST VOLTAGE 25V
J 2
(-9100 3325);
DISPLAY 0.489362 (-9100 3325);
PAINT SKYBLUE (-9100 3325);
FORCEPROP 1 LAST MATERIAL X7R
J 2
(-9100 3225);
DISPLAY 0.489362 (-9100 3225);
PAINT SKYBLUE (-9100 3225);
FORCEPROP 1 LAST VALUE 0.1UF
J 2
(-9100 3375);
DISPLAY 0.489362 (-9100 3375);
PAINT SKYBLUE (-9100 3375);
FORCEPROP 1 LAST PACK_TYPE 0402
J 2
(-9100 3125);
DISPLAY 0.489362 (-9100 3125);
PAINT SKYBLUE (-9100 3125);
FORCEPROP 1 LAST PART_NUMBER CH4104K1B00
J 2
(-9100 3175);
DISPLAY 0.489362 (-9100 3175);
PAINT SKYBLUE (-9100 3175);
FORCEPROP 0 LAST BOM_COST MEM
J 2
(-9105 3470);
DISPLAY 0.595745 (-9105 3470);
PAINT MONO (-9105 3470);
DISPLAY INVISIBLE (-9105 3470);
FORCEPROP 2 LAST CDS_LIB pure_quanta
J 0
(-9050 3325);
DISPLAY INVISIBLE (-9050 3325);
FORCEPROP 1 LAST PATH I362
J 2
(-9100 3475);
DISPLAY 0.978723 (-9100 3475);
PAINT WHITE (-9100 3475);
DISPLAY INVISIBLE (-9100 3475);
FORCEPROP 0 LAST ROOM MEM_CH_A_CPU0_DIMM1
J 2
(-9105 3470);
DISPLAY 0.595745 (-9105 3470);
PAINT RED (-9105 3470);
DISPLAY INVISIBLE (-9105 3470);
FORCEADD OFFPAGE..6
(-9175 2275);
FORCEPROP 2 LAST $XR5 81 
J 0
(-9544 2311);
DISPLAY 0.638298 (-9544 2311);
PAINT MONO (-9544 2311);
FORCEPROP 2 LAST $XR4 90 
J 0
(-9454 2311);
DISPLAY 0.638298 (-9454 2311);
PAINT MONO (-9454 2311);
FORCEPROP 2 LAST $XR3 89 
J 0
(-9544 2239);
DISPLAY 0.638298 (-9544 2239);
PAINT MONO (-9544 2239);
FORCEPROP 2 LAST $XR2 88 
J 0
(-9454 2239);
DISPLAY 0.638298 (-9454 2239);
PAINT MONO (-9454 2239);
FORCEPROP 2 LAST $XR1 87 
J 0
(-9544 2275);
DISPLAY 0.638298 (-9544 2275);
PAINT MONO (-9544 2275);
FORCEPROP 2 LAST $XR0 85 
J 0
(-9454 2275);
DISPLAY 0.638298 (-9454 2275);
PAINT MONO (-9454 2275);
FORCEPROP 2 LAST PATH I363
J 0
(-9125 2350);
DISPLAY 1.021277 (-9125 2350);
DISPLAY INVISIBLE (-9125 2350);
FORCEPROP 1 LAST COMMENT_BODY TRUE
J 0
(-9075 2200);
DISPLAY 0.872340 (-9075 2200);
PAINT GREEN (-9075 2200);
DISPLAY INVISIBLE (-9075 2200);
FORCEPROP 1 LAST OFFPAGE TRUE
J 0
(-8850 2150);
DISPLAY 0.872340 (-8850 2150);
PAINT GREEN (-8850 2150);
DISPLAY INVISIBLE (-8850 2150);
FORCEPROP 2 LAST CDS_LIB mstr_standard
J 0
(-9175 2275);
DISPLAY 0.808511 (-9175 2275);
DISPLAY INVISIBLE (-9175 2275);
FORCEADD Q_RES..1
R 2
(-8675 2275);
FORCEPROP 1 LAST LOCATION R292
J 2
(-8650 2300);
DISPLAY 0.489362 (-8650 2300);
PAINT SKYBLUE (-8650 2300);
FORCEPROP 0 LAST $SEC 1
J 0
(-8650 2350);
DISPLAY 0.680851 (-8650 2350);
PAINT MONO (-8650 2350);
DISPLAY INVISIBLE (-8650 2350);
FORCEPROP 0 LAST CDS_SEC 1
J 0
(-8650 2350);
DISPLAY 1.021277 (-8650 2350);
DISPLAY INVISIBLE (-8650 2350);
FORCEPROP 1 LASTPIN (-8575 2275) $PN 1
J 2
(-8587 2287);
DISPLAY 0.489362 (-8587 2287);
PAINT MONO (-8587 2287);
FORCEPROP 1 LASTPIN (-8775 2275) $PN 2
J 2
(-8737 2287);
DISPLAY 0.489362 (-8737 2287);
PAINT MONO (-8737 2287);
FORCEPROP 1 LAST VALUE 0
J 0
(-8675 2225);
DISPLAY 0.489362 (-8675 2225);
PAINT SKYBLUE (-8675 2225);
FORCEPROP 2 LAST BOM_COST MEM
J 0
(-8700 2425);
DISPLAY 0.744681 (-8700 2425);
PAINT WHITE (-8700 2425);
DISPLAY INVISIBLE (-8700 2425);
FORCEPROP 2 LAST CDS_LIB pure_quanta
J 0
(-8675 2275);
DISPLAY INVISIBLE (-8675 2275);
FORCEPROP 1 LAST PATH I364
J 2
(-8625 2425);
DISPLAY 0.978723 (-8625 2425);
PAINT WHITE (-8625 2425);
DISPLAY INVISIBLE (-8625 2425);
FORCEPROP 1 LAST WATTAGE 1/16W
J 0
(-8600 2200);
DISPLAY 0.489362 (-8600 2200);
PAINT SKYBLUE (-8600 2200);
DISPLAY INVISIBLE (-8600 2200);
FORCEPROP 1 LAST MATERIAL CHIP
J 0
(-8850 2250);
DISPLAY 0.489362 (-8850 2250);
PAINT SKYBLUE (-8850 2250);
DISPLAY INVISIBLE (-8850 2250);
FORCEPROP 1 LAST TOLERANCE 5%
J 2
(-8550 2250);
DISPLAY 0.489362 (-8550 2250);
PAINT SKYBLUE (-8550 2250);
DISPLAY INVISIBLE (-8550 2250);
FORCEPROP 1 LAST PART_NUMBER CS00002JB38
J 0
(-8775 2325);
DISPLAY 0.489362 (-8775 2325);
PAINT SKYBLUE (-8775 2325);
DISPLAY INVISIBLE (-8775 2325);
FORCEPROP 1 LAST PACK_TYPE 0402LF
J 0
(-8850 2200);
DISPLAY 0.489362 (-8850 2200);
PAINT SKYBLUE (-8850 2200);
DISPLAY INVISIBLE (-8850 2200);
FORCEPROP 2 LAST ROOM RST_CPU0_PLD_TO_DIMM
J 0
(-8700 2375);
DISPLAY 0.744681 (-8700 2375);
PAINT RED (-8700 2375);
DISPLAY INVISIBLE (-8700 2375);
FORCEADD Q_RES..2
(-8550 2425);
FORCEPROP 1 LAST LOCATION R90
J 0
(-8505 2550);
DISPLAY 0.489362 (-8505 2550);
PAINT SKYBLUE (-8505 2550);
FORCEPROP 0 LAST $SEC 1
J 0
(-8500 2600);
DISPLAY 0.680851 (-8500 2600);
PAINT MONO (-8500 2600);
DISPLAY INVISIBLE (-8500 2600);
FORCEPROP 0 LAST CDS_SEC 1
J 0
(-8500 2600);
DISPLAY 1.021277 (-8500 2600);
DISPLAY INVISIBLE (-8500 2600);
FORCEPROP 1 LASTPIN (-8550 2525) $PN 1
J 0
(-8545 2487);
DISPLAY 0.489362 (-8545 2487);
PAINT MONO (-8545 2487);
FORCEPROP 1 LASTPIN (-8550 2325) $PN 2
J 0
(-8545 2335);
DISPLAY 0.489362 (-8545 2335);
PAINT MONO (-8545 2335);
FORCEPROP 1 LAST PACK_TYPE 0402LF
J 0
(-8500 2375);
DISPLAY 0.489362 (-8500 2375);
PAINT SKYBLUE (-8500 2375);
FORCEPROP 1 LAST VALUE 1K
J 0
(-8505 2500);
DISPLAY 0.489362 (-8505 2500);
PAINT SKYBLUE (-8505 2500);
FORCEPROP 1 LAST TOLERANCE 5%
J 0
(-8500 2475);
DISPLAY 0.489362 (-8500 2475);
PAINT SKYBLUE (-8500 2475);
FORCEPROP 1 LAST MATERIAL EMPTY
J 0
(-8500 2425);
DISPLAY 0.489362 (-8500 2425);
PAINT RED (-8500 2425);
FORCEPROP 1 LAST WATTAGE 1/16W
J 0
(-8500 2450);
DISPLAY 0.489362 (-8500 2450);
PAINT SKYBLUE (-8500 2450);
FORCEPROP 2 LAST CDS_LIB pure_quanta
J 2
(-8550 2425);
DISPLAY INVISIBLE (-8550 2425);
FORCEPROP 2 LAST BOM_COST MEM
J 0
(-8500 2600);
DISPLAY 0.808511 (-8500 2600);
DISPLAY INVISIBLE (-8500 2600);
FORCEPROP 1 LAST PATH I365
J 0
(-8500 2600);
DISPLAY 0.978723 (-8500 2600);
PAINT WHITE (-8500 2600);
DISPLAY INVISIBLE (-8500 2600);
FORCEPROP 1 LAST PART_NUMBER TMP_QCS21002JB34
J 0
(-8500 2400);
DISPLAY 0.489362 (-8500 2400);
PAINT SKYBLUE (-8500 2400);
DISPLAY INVISIBLE (-8500 2400);
FORCEPROP 2 LAST ROOM MEM_CH_A_CPU0_DIMM1
J 0
(-8500 2650);
DISPLAY 0.808511 (-8500 2650);
PAINT RED (-8500 2650);
DISPLAY INVISIBLE (-8500 2650);
FORCEADD VCC_CORE..1
(-8550 2600);
FORCEPROP 3 LASTPIN (-8550 2550) SIG_NAME P3V3_STBY\g
J 0
(-8540 2560);
DISPLAY 0.659574 (-8540 2560);
PAINT MONO (-8540 2560);
DISPLAY INVISIBLE (-8540 2560);
FORCEPROP 1 LAST HDL_POWER P3V3_STBY
J 1
(-8550 2650);
DISPLAY 0.489362 (-8550 2650);
PAINT GREEN (-8550 2650);
FORCEPROP 2 LAST CDS_LIB mstr_symbols
J 0
(-8550 2600);
DISPLAY INVISIBLE (-8550 2600);
FORCEPROP 1 LAST PATH I366
J 0
(-8500 2625);
DISPLAY 0.872340 (-8500 2625);
PAINT AQUA (-8500 2625);
DISPLAY INVISIBLE (-8500 2625);
FORCEPROP 0 LAST VOLTAGE 3.3
J 0
(-8825 2750);
DISPLAY 1.021277 (-8825 2750);
PAINT SKYBLUE (-8825 2750);
DISPLAY INVISIBLE (-8825 2750);
FORCEPROP 2 LAST ROOM PVCCINFAON_CPU0_CTRL
J 0
(-8550 2700);
DISPLAY 0.808511 (-8550 2700);
PAINT RED (-8550 2700);
DISPLAY INVISIBLE (-8550 2700);
FORCEADD SCONN288_DDR506112002KQ..2
(-4600 3650);
FORCEPROP 1 LAST LOCATION J15
J 0
(-5200 4975);
DISPLAY 0.574468 (-5200 4975);
PAINT SKYBLUE (-5200 4975);
FORCEPROP 0 LAST $SEC 2
J 0
(-5200 5150);
DISPLAY 0.680851 (-5200 5150);
PAINT MONO (-5200 5150);
DISPLAY INVISIBLE (-5200 5150);
FORCEPROP 0 LAST CDS_SEC 2
J 0
(-5050 5125);
DISPLAY 1.021277 (-5050 5125);
DISPLAY INVISIBLE (-5050 5125);
FORCEPROP 0 LASTPIN (-3850 3700) $PN 12
J 0
(-3840 3710);
DISPLAY 0.680851 (-3840 3710);
PAINT MONO (-3840 3710);
FORCEPROP 0 LASTPIN (-3850 3750) $PN 11
J 0
(-3840 3760);
DISPLAY 0.680851 (-3840 3760);
PAINT MONO (-3840 3760);
FORCEPROP 0 LASTPIN (-3850 2650) $PN 105
J 0
(-3840 2660);
DISPLAY 0.680851 (-3840 2660);
PAINT MONO (-3840 2660);
FORCEPROP 0 LASTPIN (-3850 2700) $PN 104
J 0
(-3840 2710);
DISPLAY 0.680851 (-3840 2710);
PAINT MONO (-3840 2710);
FORCEPROP 0 LASTPIN (-3850 3800) $PN 23
J 0
(-3840 3810);
DISPLAY 0.680851 (-3840 3810);
PAINT MONO (-3840 3810);
FORCEPROP 0 LASTPIN (-3850 3850) $PN 22
J 0
(-3840 3860);
DISPLAY 0.680851 (-3840 3860);
PAINT MONO (-3840 3860);
FORCEPROP 0 LASTPIN (-3850 2750) $PN 116
J 0
(-3840 2760);
DISPLAY 0.680851 (-3840 2760);
PAINT MONO (-3840 2760);
FORCEPROP 0 LASTPIN (-3850 2800) $PN 115
J 0
(-3840 2810);
DISPLAY 0.680851 (-3840 2810);
PAINT MONO (-3840 2810);
FORCEPROP 0 LASTPIN (-3850 3900) $PN 34
J 0
(-3840 3910);
DISPLAY 0.680851 (-3840 3910);
PAINT MONO (-3840 3910);
FORCEPROP 0 LASTPIN (-3850 3950) $PN 33
J 0
(-3840 3960);
DISPLAY 0.680851 (-3840 3960);
PAINT MONO (-3840 3960);
FORCEPROP 0 LASTPIN (-3850 2850) $PN 127
J 0
(-3840 2860);
DISPLAY 0.680851 (-3840 2860);
PAINT MONO (-3840 2860);
FORCEPROP 0 LASTPIN (-3850 2900) $PN 126
J 0
(-3840 2910);
DISPLAY 0.680851 (-3840 2910);
PAINT MONO (-3840 2910);
FORCEPROP 0 LASTPIN (-3850 4000) $PN 45
J 0
(-3840 4010);
DISPLAY 0.680851 (-3840 4010);
PAINT MONO (-3840 4010);
FORCEPROP 0 LASTPIN (-3850 4050) $PN 44
J 0
(-3840 4060);
DISPLAY 0.680851 (-3840 4060);
PAINT MONO (-3840 4060);
FORCEPROP 0 LASTPIN (-3850 2950) $PN 138
J 0
(-3840 2960);
DISPLAY 0.680851 (-3840 2960);
PAINT MONO (-3840 2960);
FORCEPROP 0 LASTPIN (-3850 3000) $PN 137
J 0
(-3840 3010);
DISPLAY 0.680851 (-3840 3010);
PAINT MONO (-3840 3010);
FORCEPROP 0 LASTPIN (-3850 4100) $PN 56
J 0
(-3840 4110);
DISPLAY 0.680851 (-3840 4110);
PAINT MONO (-3840 4110);
FORCEPROP 0 LASTPIN (-3850 4150) $PN 55
J 0
(-3840 4160);
DISPLAY 0.680851 (-3840 4160);
PAINT MONO (-3840 4160);
FORCEPROP 0 LASTPIN (-3850 3050) $PN 238
J 0
(-3840 3060);
DISPLAY 0.680851 (-3840 3060);
PAINT MONO (-3840 3060);
FORCEPROP 0 LASTPIN (-3850 3100) $PN 239
J 0
(-3840 3110);
DISPLAY 0.680851 (-3840 3110);
PAINT MONO (-3840 3110);
FORCEPROP 0 LASTPIN (-3850 4200) $PN 156
J 0
(-3840 4210);
DISPLAY 0.680851 (-3840 4210);
PAINT MONO (-3840 4210);
FORCEPROP 0 LASTPIN (-3850 4250) $PN 157
J 0
(-3840 4260);
DISPLAY 0.680851 (-3840 4260);
PAINT MONO (-3840 4260);
FORCEPROP 0 LASTPIN (-3850 3150) $PN 249
J 0
(-3840 3160);
DISPLAY 0.680851 (-3840 3160);
PAINT MONO (-3840 3160);
FORCEPROP 0 LASTPIN (-3850 3200) $PN 250
J 0
(-3840 3210);
DISPLAY 0.680851 (-3840 3210);
PAINT MONO (-3840 3210);
FORCEPROP 0 LASTPIN (-3850 4300) $PN 167
J 0
(-3840 4310);
DISPLAY 0.680851 (-3840 4310);
PAINT MONO (-3840 4310);
FORCEPROP 0 LASTPIN (-3850 4350) $PN 168
J 0
(-3840 4360);
DISPLAY 0.680851 (-3840 4360);
PAINT MONO (-3840 4360);
FORCEPROP 0 LASTPIN (-3850 3250) $PN 260
J 0
(-3840 3260);
DISPLAY 0.680851 (-3840 3260);
PAINT MONO (-3840 3260);
FORCEPROP 0 LASTPIN (-3850 3300) $PN 261
J 0
(-3840 3310);
DISPLAY 0.680851 (-3840 3310);
PAINT MONO (-3840 3310);
FORCEPROP 0 LASTPIN (-3850 4400) $PN 178
J 0
(-3840 4410);
DISPLAY 0.680851 (-3840 4410);
PAINT MONO (-3840 4410);
FORCEPROP 0 LASTPIN (-3850 4450) $PN 179
J 0
(-3840 4460);
DISPLAY 0.680851 (-3840 4460);
PAINT MONO (-3840 4460);
FORCEPROP 0 LASTPIN (-3850 3350) $PN 271
J 0
(-3840 3360);
DISPLAY 0.680851 (-3840 3360);
PAINT MONO (-3840 3360);
FORCEPROP 0 LASTPIN (-3850 3400) $PN 272
J 0
(-3840 3410);
DISPLAY 0.680851 (-3840 3410);
PAINT MONO (-3840 3410);
FORCEPROP 0 LASTPIN (-3850 4500) $PN 189
J 0
(-3840 4510);
DISPLAY 0.680851 (-3840 4510);
PAINT MONO (-3840 4510);
FORCEPROP 0 LASTPIN (-3850 4550) $PN 190
J 0
(-3840 4560);
DISPLAY 0.680851 (-3840 4560);
PAINT MONO (-3840 4560);
FORCEPROP 0 LASTPIN (-3850 3450) $PN 282
J 0
(-3840 3460);
DISPLAY 0.680851 (-3840 3460);
PAINT MONO (-3840 3460);
FORCEPROP 0 LASTPIN (-3850 3500) $PN 283
J 0
(-3840 3510);
DISPLAY 0.680851 (-3840 3510);
PAINT MONO (-3840 3510);
FORCEPROP 0 LASTPIN (-3850 4600) $PN 200
J 0
(-3840 4610);
DISPLAY 0.680851 (-3840 4610);
PAINT MONO (-3840 4610);
FORCEPROP 0 LASTPIN (-3850 4650) $PN 201
J 0
(-3840 4660);
DISPLAY 0.680851 (-3840 4660);
PAINT MONO (-3840 4660);
FORCEPROP 0 LASTPIN (-3850 3550) $PN 94
J 0
(-3840 3560);
DISPLAY 0.680851 (-3840 3560);
PAINT MONO (-3840 3560);
FORCEPROP 0 LASTPIN (-3850 3600) $PN 93
J 0
(-3840 3610);
DISPLAY 0.680851 (-3840 3610);
PAINT MONO (-3840 3610);
FORCEPROP 1 LAST MATERIAL IO
J 0
(-5200 4825);
DISPLAY 0.468085 (-5200 4825);
PAINT SKYBLUE (-5200 4825);
FORCEPROP 1 LAST PART_NUMBER DFHST8FS479
J 0
(-5200 4900);
DISPLAY 0.468085 (-5200 4900);
PAINT SKYBLUE (-5200 4900);
FORCEPROP 2 LAST VALUE SCONN288_DDR506112002KQ
J 0
(-5200 5050);
DISPLAY 0.489362 (-5200 5050);
PAINT SKYBLUE (-5200 5050);
FORCEPROP 2 LAST PART_TYPE SMLF
J 0
(-5200 5100);
DISPLAY 1.021277 (-5200 5100);
FORCEPROP 1 LAST CDS_LMAN_SYM_OUTLINE -600,1150,600,-1150
J 0
(-4600 3650);
DISPLAY 0.468085 (-4600 3650);
PAINT GREEN (-4600 3650);
DISPLAY INVISIBLE (-4600 3650);
FORCEPROP 1 LAST PATH I367
J 0
(-4600 3650);
DISPLAY 0.723404 (-4600 3650);
PAINT GREEN (-4600 3650);
DISPLAY INVISIBLE (-4600 3650);
FORCEPROP 1 LAST NEEDS_NO_SIZE TRUE
J 0
(-4600 3650);
DISPLAY 0.723404 (-4600 3650);
PAINT GREEN (-4600 3650);
DISPLAY INVISIBLE (-4600 3650);
FORCEPROP 2 LAST CDS_LIB pure_quanta
J 0
(-4600 3650);
DISPLAY INVISIBLE (-4600 3650);
FORCEADD GND..1
(-2825 5225);
FORCEPROP 3 LASTPIN (-2825 5275) SIG_NAME GND\g
J 0
(-2815 5285);
DISPLAY 0.659574 (-2815 5285);
PAINT MONO (-2815 5285);
DISPLAY INVISIBLE (-2815 5285);
FORCEPROP 1 LAST SIZE 1B
J 0
(-2750 5175);
DISPLAY 0.723404 (-2750 5175);
PAINT GREEN (-2750 5175);
DISPLAY INVISIBLE (-2750 5175);
FORCEPROP 2 LAST BOM_COST MEM
J 0
(-2800 5350);
DISPLAY 0.659574 (-2800 5350);
DISPLAY INVISIBLE (-2800 5350);
FORCEPROP 2 LAST CDS_LIB pure_quanta_power
J 0
(-2825 5225);
DISPLAY INVISIBLE (-2825 5225);
FORCEPROP 1 LAST PATH I368
J 0
(-2750 5225);
DISPLAY 0.872340 (-2750 5225);
PAINT AQUA (-2750 5225);
DISPLAY INVISIBLE (-2750 5225);
FORCEPROP 2 LAST ROOM MEM_EFGH_DECOUPLING_CAPS
J 0
(-2800 5300);
DISPLAY 0.659574 (-2800 5300);
PAINT RED (-2800 5300);
DISPLAY INVISIBLE (-2800 5300);
FORCEPROP 1 LAST HDL_POWER GND
J 0
(-2825 5375);
DISPLAY 0.723404 (-2825 5375);
PAINT GREEN (-2825 5375);
DISPLAY INVISIBLE (-2825 5375);
FORCEADD Q_CAP..1
R 2
(-2825 5575);
FORCEPROP 1 LAST LOCATION C143
J 2
(-2875 5675);
DISPLAY 0.489362 (-2875 5675);
PAINT SKYBLUE (-2875 5675);
FORCEPROP 0 LAST $SEC 1
J 0
(-2875 5725);
DISPLAY 0.680851 (-2875 5725);
PAINT MONO (-2875 5725);
DISPLAY INVISIBLE (-2875 5725);
FORCEPROP 0 LAST CDS_SEC 1
J 0
(-2875 5725);
DISPLAY 0.680851 (-2875 5725);
DISPLAY INVISIBLE (-2875 5725);
FORCEPROP 1 LASTPIN (-2825 5675) $PN 1
J 2
(-2835 5655);
DISPLAY 0.489362 (-2835 5655);
PAINT MONO (-2835 5655);
FORCEPROP 1 LASTPIN (-2825 5475) $PN 2
J 2
(-2835 5455);
DISPLAY 0.489362 (-2835 5455);
PAINT MONO (-2835 5455);
FORCEPROP 1 LAST MATERIAL X6S
J 2
(-2875 5475);
DISPLAY 0.489362 (-2875 5475);
PAINT SKYBLUE (-2875 5475);
FORCEPROP 1 LAST TOLERANCE 10%
J 2
(-2875 5525);
DISPLAY 0.489362 (-2875 5525);
PAINT SKYBLUE (-2875 5525);
FORCEPROP 1 LAST VALUE 10UF
J 2
(-2875 5625);
DISPLAY 0.489362 (-2875 5625);
PAINT SKYBLUE (-2875 5625);
FORCEPROP 1 LAST VOLTAGE 25V
J 2
(-2875 5575);
DISPLAY 0.489362 (-2875 5575);
PAINT SKYBLUE (-2875 5575);
FORCEPROP 1 LAST PACK_TYPE C0805
J 2
(-2875 5375);
DISPLAY 0.489362 (-2875 5375);
PAINT SKYBLUE (-2875 5375);
FORCEPROP 1 LAST PART_NUMBER CH6104KEA00
J 2
(-2875 5425);
DISPLAY 0.489362 (-2875 5425);
PAINT SKYBLUE (-2875 5425);
FORCEPROP 2 LAST CDS_LIB pure_quanta
J 0
(-2825 5575);
DISPLAY INVISIBLE (-2825 5575);
FORCEPROP 0 LAST BOM_COST MEM
J 2
(-2880 5720);
DISPLAY 0.595745 (-2880 5720);
PAINT MONO (-2880 5720);
DISPLAY INVISIBLE (-2880 5720);
FORCEPROP 1 LAST PATH I369
J 2
(-2875 5725);
DISPLAY 0.978723 (-2875 5725);
PAINT WHITE (-2875 5725);
DISPLAY INVISIBLE (-2875 5725);
FORCEPROP 0 LAST ROOM MEM_CH_A_CPU0_DIMM1
J 2
(-2880 5720);
DISPLAY 0.595745 (-2880 5720);
PAINT RED (-2880 5720);
DISPLAY INVISIBLE (-2880 5720);
FORCEADD Q_CAP..1
R 2
(-2250 5575);
FORCEPROP 1 LAST LOCATION C145
J 2
(-2300 5675);
DISPLAY 0.489362 (-2300 5675);
PAINT SKYBLUE (-2300 5675);
FORCEPROP 0 LAST $SEC 1
J 0
(-2300 5725);
DISPLAY 0.680851 (-2300 5725);
PAINT MONO (-2300 5725);
DISPLAY INVISIBLE (-2300 5725);
FORCEPROP 0 LAST CDS_SEC 1
J 0
(-2300 5725);
DISPLAY 0.680851 (-2300 5725);
DISPLAY INVISIBLE (-2300 5725);
FORCEPROP 1 LASTPIN (-2250 5675) $PN 1
J 2
(-2260 5655);
DISPLAY 0.489362 (-2260 5655);
PAINT MONO (-2260 5655);
FORCEPROP 1 LASTPIN (-2250 5475) $PN 2
J 2
(-2260 5455);
DISPLAY 0.489362 (-2260 5455);
PAINT MONO (-2260 5455);
FORCEPROP 1 LAST MATERIAL X6S
J 2
(-2300 5475);
DISPLAY 0.489362 (-2300 5475);
PAINT SKYBLUE (-2300 5475);
FORCEPROP 1 LAST TOLERANCE 10%
J 2
(-2300 5525);
DISPLAY 0.489362 (-2300 5525);
PAINT SKYBLUE (-2300 5525);
FORCEPROP 1 LAST VALUE 10UF
J 2
(-2300 5625);
DISPLAY 0.489362 (-2300 5625);
PAINT SKYBLUE (-2300 5625);
FORCEPROP 1 LAST PART_NUMBER CH6104KEA00
J 2
(-2300 5425);
DISPLAY 0.489362 (-2300 5425);
PAINT SKYBLUE (-2300 5425);
FORCEPROP 1 LAST VOLTAGE 25V
J 2
(-2300 5575);
DISPLAY 0.489362 (-2300 5575);
PAINT SKYBLUE (-2300 5575);
FORCEPROP 1 LAST PACK_TYPE C0805
J 2
(-2300 5375);
DISPLAY 0.489362 (-2300 5375);
PAINT SKYBLUE (-2300 5375);
FORCEPROP 2 LAST CDS_LIB pure_quanta
J 0
(-2250 5575);
DISPLAY INVISIBLE (-2250 5575);
FORCEPROP 0 LAST BOM_COST MEM
J 2
(-2305 5720);
DISPLAY 0.595745 (-2305 5720);
PAINT MONO (-2305 5720);
DISPLAY INVISIBLE (-2305 5720);
FORCEPROP 1 LAST PATH I370
J 2
(-2300 5725);
DISPLAY 0.978723 (-2300 5725);
PAINT WHITE (-2300 5725);
DISPLAY INVISIBLE (-2300 5725);
FORCEPROP 0 LAST ROOM MEM_CH_A_CPU0_DIMM1
J 2
(-2305 5720);
DISPLAY 0.595745 (-2305 5720);
PAINT RED (-2305 5720);
DISPLAY INVISIBLE (-2305 5720);
FORCEADD UNIVERSAL_POWER..1
(-2825 5900);
FORCEPROP 3 LASTPIN (-2825 5850) SIG_NAME P12V_MEM_1\g
J 0
(-2815 5860);
DISPLAY 0.659574 (-2815 5860);
PAINT MONO (-2815 5860);
DISPLAY INVISIBLE (-2815 5860);
FORCEPROP 1 LAST HDL_POWER P12V_MEM_1
J 1
(-2850 5950);
DISPLAY 0.489362 (-2850 5950);
PAINT GREEN (-2850 5950);
FORCEPROP 2 LAST BOM_COST VR_SYSTEM
J 0
(-2825 6000);
DISPLAY 0.617021 (-2825 6000);
PAINT PURPLE (-2825 6000);
DISPLAY INVISIBLE (-2825 6000);
FORCEPROP 2 LAST CDS_LIB pure_quanta_power
J 0
(-2825 5900);
DISPLAY INVISIBLE (-2825 5900);
FORCEPROP 1 LAST PATH I371
J 0
(-2775 5925);
DISPLAY 0.872340 (-2775 5925);
PAINT AQUA (-2775 5925);
DISPLAY INVISIBLE (-2775 5925);
FORCEADD Q_RES..1
(-8000 2825);
FORCEPROP 1 LAST $LOCATION R1569
J 0
(-8050 2850);
DISPLAY 0.510638 (-8050 2850);
PAINT SKYBLUE (-8050 2850);
FORCEPROP 0 LAST CDS_LOCATION R1569
J 0
(-8050 2925);
DISPLAY 0.680851 (-8050 2925);
DISPLAY INVISIBLE (-8050 2925);
FORCEPROP 0 LAST $SEC 1
J 0
(-8050 2925);
DISPLAY 0.680851 (-8050 2925);
PAINT MONO (-8050 2925);
DISPLAY INVISIBLE (-8050 2925);
FORCEPROP 0 LAST CDS_SEC 1
J 0
(-8050 2925);
DISPLAY 0.680851 (-8050 2925);
DISPLAY INVISIBLE (-8050 2925);
FORCEPROP 1 LASTPIN (-8100 2825) $PN 1
J 0
(-8088 2837);
DISPLAY 0.787234 (-8088 2837);
PAINT MONO (-8088 2837);
FORCEPROP 1 LASTPIN (-7900 2825) $PN 2
J 0
(-7938 2837);
DISPLAY 0.787234 (-7938 2837);
PAINT MONO (-7938 2837);
FORCEPROP 1 LAST VALUE 49.9
J 2
(-7875 2900);
DISPLAY 0.510638 (-7875 2900);
PAINT SKYBLUE (-7875 2900);
FORCEPROP 1 LAST PART_NUMBER CS04992FB07
J 0
(-8050 2925);
DISPLAY 0.978723 (-8050 2925);
DISPLAY INVISIBLE (-8050 2925);
FORCEPROP 1 LAST TOLERANCE 1%
J 0
(-8000 2725);
DISPLAY 0.978723 (-8000 2725);
DISPLAY INVISIBLE (-8000 2725);
FORCEPROP 1 LAST WATTAGE 1/16W
J 2
(-8025 2675);
DISPLAY 0.978723 (-8025 2675);
DISPLAY INVISIBLE (-8025 2675);
FORCEPROP 1 LAST PACK_TYPE 0402LF
J 0
(-7750 2675);
DISPLAY 0.978723 (-7750 2675);
DISPLAY INVISIBLE (-7750 2675);
FORCEPROP 1 LAST MATERIAL CHIP
J 0
(-8000 2675);
DISPLAY 0.978723 (-8000 2675);
DISPLAY INVISIBLE (-8000 2675);
FORCEPROP 1 LAST PATH I372
J 0
(-8050 2975);
DISPLAY 0.978723 (-8050 2975);
PAINT WHITE (-8050 2975);
DISPLAY INVISIBLE (-8050 2975);
FORCEPROP 2 LAST CDS_LIB pure_quanta
J 0
(-8000 2825);
DISPLAY INVISIBLE (-8000 2825);
FORCEADD QUANTA_TITLE_BLOCK_C..1
(-100 100);
FORCEPROP 0 LAST CDS_CON_LAST_MODIFIED Fri Mar 11 14:52:53 2022
J 0
(-1985 115);
DISPLAY INVISIBLE (-1985 115);
FORCEPROP 1 LAST CUSTOM_TXT_CDS <CON_LAST_MODIFIED>
J 0
(-1985 115);
DISPLAY 0.978723 (-1985 115);
FORCEPROP 2 LAST CUSTOM_TXT_CDS <XR_PAGE_TITLE>
J 0
(-7990 5350);
DISPLAY 0.638298 (-7990 5350);
PAINT PINK (-7990 5350);
DISPLAY INVISIBLE (-7990 5350);
FORCEPROP 1 LAST CUSTOM_TXT_CDS <NAME_2>
J 0
(-3275 150);
FORCEPROP 1 LAST CUSTOM_TXT_CDS <NAME_1>
J 0
(-3275 275);
FORCEPROP 1 LAST CUSTOM_TXT_CDS <Q_NUMBER>
J 0
(-1503 203);
DISPLAY 1.212766 (-1503 203);
FORCEPROP 1 LAST CUSTOM_TXT_CDS <Q_PROJ>
J 0
(-2482 202);
DISPLAY 1.212766 (-2482 202);
FORCEPROP 1 LAST CUSTOM_TXT_CDS <Q_REV>
J 0
(-284 203);
DISPLAY 1.212766 (-284 203);
FORCEPROP 1 LAST CUSTOM_TXT_CDS <CON_PAGE_NUM> OF <CON_TOTAL_PAGES>
J 0
(-546 118);
DISPLAY 0.978723 (-546 118);
FORCEPROP 1 LAST Q_TITLE DDR5 - CPU0 CHB
J 0
(-9425 150);
DISPLAY 2.446809 (-9425 150);
PAINT GREEN (-9425 150);
FORCEPROP 1 LAST Q_DEPT BU9
J 1
(-3863 149);
DISPLAY 1.957447 (-3863 149);
PAINT GREEN (-3863 149);
FORCEPROP 2 LAST PAGE_BORDER TRUE
J 0
(-7990 5350);
DISPLAY 0.638298 (-7990 5350);
PAINT PINK (-7990 5350);
DISPLAY INVISIBLE (-7990 5350);
FORCEPROP 1 LAST CDS_LMAN_SYM_OUTLINE -9475,6775,100,-125
J 0
(-100 100);
DISPLAY 0.468085 (-100 100);
PAINT GREEN (-100 100);
DISPLAY INVISIBLE (-100 100);
FORCEPROP 2 LAST CDS_LIB pure_quanta
J 0
(-100 100);
DISPLAY INVISIBLE (-100 100);
FORCEPROP 1 LAST COMMENT_BODY TRUE
J 0
(-88 87);
DISPLAY 0.978723 (-88 87);
PAINT GREEN (-88 87);
DISPLAY INVISIBLE (-88 87);
FORCEPROP 2 LAST CDS_XR_PAGE_TITLE CR-86 : @T6G_MB_LIB.T6G(SCH_1):PAGE86
J 0
(-7990 5350);
DISPLAY 0.638298 (-7990 5350);
PAINT PINK (-7990 5350);
DISPLAY INVISIBLE (-7990 5350);
FORCEADD DNS..2
(-8525 2425);
PAINT RED (-8525 2425);
FORCEPROP 2 LAST CDS_LIB mstr_misc
J 0
(-8525 2425);
DISPLAY INVISIBLE (-8525 2425);
FORCEPROP 1 LAST COMMENT_BODY TRUE
R 1
J 0
(-8450 2200);
DISPLAY 0.872340 (-8450 2200);
PAINT PEACH (-8450 2200);
DISPLAY INVISIBLE (-8450 2200);
WIRE 17 -1 (-6200 5550)(-6200 5500);
WIRE 17 -1 (-6200 5575)(-6200 5550);
WIRE 17 -1 (-6200 5500)(-6200 5450);
WIRE 17 -1 (-6200 5450)(-6200 5400);
WIRE 17 -1 (-6200 5575)(-5550 5575);
FORCEPROP 2 LAST SIG_NAME M_B_CPU0_SA_DQ<31:0>
J 0
(-6135 5585);
DISPLAY 0.489362 (-6135 5585);
WIRE 17 -1 (-8000 4150)(-8000 4100);
WIRE 17 -1 (-8000 4150)(-8000 4175);
WIRE 17 -1 (-8000 4050)(-8000 4100);
WIRE 17 -1 (-8000 4050)(-8000 4000);
WIRE 17 -1 (-8000 4175)(-8500 4175);
FORCEPROP 2 LAST SIG_NAME M_B_CPU0_SA_CB<7:0>
J 0
(-8450 4185);
DISPLAY 0.489362 (-8450 4185);
WIRE 17 -1 (-8000 3950)(-8000 4000);
WIRE 17 -1 (-8000 3900)(-8000 3950);
WIRE 17 -1 (-8000 3850)(-8000 3900);
WIRE 17 -1 (-8000 3800)(-8000 3850);
WIRE 17 -1 (-8000 3700)(-8000 3650);
WIRE 17 -1 (-8000 3700)(-8000 3725);
WIRE 17 -1 (-8000 3600)(-8000 3650);
WIRE 17 -1 (-8000 3600)(-8000 3550);
WIRE 17 -1 (-8000 3725)(-8500 3725);
FORCEPROP 2 LAST SIG_NAME M_B_CPU0_SB_CB<7:0>
J 0
(-8450 3735);
DISPLAY 0.489362 (-8450 3735);
WIRE 17 -1 (-8000 5250)(-8000 5300);
WIRE 17 -1 (-8000 5300)(-8000 5350);
WIRE 17 -1 (-8000 5350)(-8000 5400);
WIRE 17 -1 (-8000 5400)(-8000 5450);
WIRE 17 -1 (-8000 5450)(-8000 5500);
WIRE 17 -1 (-8000 5500)(-8000 5550);
WIRE 17 -1 (-8000 5550)(-8000 5575);
WIRE 17 -1 (-8000 5575)(-8500 5575);
FORCEPROP 2 LAST SIG_NAME M_B_CPU0_SA_CA<6:0>
J 0
(-8485 5585);
DISPLAY 0.489362 (-8485 5585);
WIRE 17 -1 (-8000 4850)(-8000 4900);
WIRE 17 -1 (-8000 4900)(-8000 4950);
WIRE 17 -1 (-8000 4950)(-8000 5000);
WIRE 17 -1 (-8000 5000)(-8000 5050);
WIRE 17 -1 (-8000 5050)(-8000 5100);
WIRE 17 -1 (-8000 5100)(-8000 5150);
WIRE 17 -1 (-8000 5150)(-8000 5175);
WIRE 17 -1 (-8000 5175)(-8500 5175);
FORCEPROP 2 LAST SIG_NAME M_B_CPU0_SB_CA<6:0>
J 0
(-8485 5185);
DISPLAY 0.489362 (-8485 5185);
WIRE 17 -1 (-8000 3500)(-8000 3550);
WIRE 17 -1 (-8000 3450)(-8000 3500);
WIRE 17 -1 (-8000 3400)(-8000 3450);
WIRE 17 -1 (-8000 3350)(-8000 3400);
WIRE 17 -1 (-6200 5400)(-6200 5350);
WIRE 17 -1 (-6200 5350)(-6200 5300);
WIRE 17 -1 (-6200 5300)(-6200 5250);
WIRE 17 -1 (-6200 5250)(-6200 5200);
WIRE 17 -1 (-6200 5200)(-6200 5150);
WIRE 17 -1 (-6200 5150)(-6200 5100);
WIRE 17 -1 (-6200 5100)(-6200 5050);
WIRE 17 -1 (-6200 5050)(-6200 5000);
WIRE 17 -1 (-6200 5000)(-6200 4950);
WIRE 17 -1 (-6200 4950)(-6200 4900);
WIRE 17 -1 (-6200 4900)(-6200 4850);
WIRE 17 -1 (-6200 4850)(-6200 4800);
WIRE 17 -1 (-6200 4750)(-6200 4800);
WIRE 17 -1 (-6200 4700)(-6200 4750);
WIRE 17 -1 (-6200 4650)(-6200 4700);
WIRE 17 -1 (-6200 4600)(-6200 4650);
WIRE 17 -1 (-6200 4600)(-6200 4550);
WIRE 17 -1 (-6200 4550)(-6200 4500);
WIRE 17 -1 (-6200 4500)(-6200 4450);
WIRE 17 -1 (-6200 4450)(-6200 4400);
WIRE 17 -1 (-6200 4400)(-6200 4350);
WIRE 17 -1 (-6200 4350)(-6200 4300);
WIRE 17 -1 (-6200 4300)(-6200 4250);
WIRE 17 -1 (-6200 4250)(-6200 4200);
WIRE 17 -1 (-6200 4150)(-6200 4200);
WIRE 17 -1 (-6200 4100)(-6200 4150);
WIRE 17 -1 (-6200 4050)(-6200 4100);
WIRE 17 -1 (-6200 4000)(-6200 4050);
WIRE 17 -1 (-6200 3900)(-6200 3850);
WIRE 17 -1 (-6200 3925)(-6200 3900);
WIRE 17 -1 (-6200 3850)(-6200 3800);
WIRE 17 -1 (-6200 3800)(-6200 3750);
WIRE 17 -1 (-6200 3925)(-5550 3925);
FORCEPROP 2 LAST SIG_NAME M_B_CPU0_SB_DQ<31:0>
J 0
(-6135 3935);
DISPLAY 0.489362 (-6135 3935);
WIRE 17 -1 (-6200 3750)(-6200 3700);
WIRE 17 -1 (-6200 3700)(-6200 3650);
WIRE 17 -1 (-6200 3650)(-6200 3600);
WIRE 17 -1 (-6200 3600)(-6200 3550);
WIRE 17 -1 (-6200 3550)(-6200 3500);
WIRE 17 -1 (-6200 3500)(-6200 3450);
WIRE 17 -1 (-6200 3450)(-6200 3400);
WIRE 17 -1 (-6200 3400)(-6200 3350);
WIRE 17 -1 (-6200 3350)(-6200 3300);
WIRE 17 -1 (-6200 3300)(-6200 3250);
WIRE 17 -1 (-6200 3250)(-6200 3200);
WIRE 17 -1 (-6200 3200)(-6200 3150);
WIRE 17 -1 (-6200 3100)(-6200 3150);
WIRE 17 -1 (-6200 3050)(-6200 3100);
WIRE 17 -1 (-6200 3000)(-6200 3050);
WIRE 17 -1 (-6200 2950)(-6200 3000);
WIRE 17 -1 (-6200 2950)(-6200 2900);
WIRE 17 -1 (-6200 2900)(-6200 2850);
WIRE 17 -1 (-6200 2850)(-6200 2800);
WIRE 17 -1 (-6200 2800)(-6200 2750);
WIRE 17 -1 (-6200 2750)(-6200 2700);
WIRE 17 -1 (-6200 2700)(-6200 2650);
WIRE 17 -1 (-6200 2650)(-6200 2600);
WIRE 17 -1 (-6200 2600)(-6200 2550);
WIRE 17 -1 (-6200 2500)(-6200 2550);
WIRE 17 -1 (-6200 2450)(-6200 2500);
WIRE 17 -1 (-6200 2400)(-6200 2450);
WIRE 17 -1 (-6200 2350)(-6200 2400);
WIRE 17 -1 (-3400 4425)(-3400 4325);
WIRE 17 -1 (-3400 4525)(-3400 4425);
WIRE 17 -1 (-3400 4325)(-3400 4225);
WIRE 17 -1 (-3400 4125)(-3400 4225);
WIRE 17 -1 (-3400 4625)(-3400 4525);
WIRE 17 -1 (-3400 4650)(-3400 4625);
WIRE 17 -1 (-3400 4025)(-3400 4125);
WIRE 17 -1 (-3400 3925)(-3400 4025);
WIRE 17 -1 (-3400 4650)(-2700 4650);
FORCEPROP 2 LAST SIG_NAME M_B_CPU0_SA_DQS_DN<9:0>
J 0
(-3335 4660);
DISPLAY 0.489362 (-3335 4660);
WIRE 17 -1 (-3600 4375)(-3600 4275);
WIRE 17 -1 (-3600 4475)(-3600 4375);
WIRE 17 -1 (-3600 4175)(-3600 4275);
WIRE 17 -1 (-3600 4075)(-3600 4175);
WIRE 17 -1 (-3600 4575)(-3600 4475);
WIRE 17 -1 (-3600 4675)(-3600 4575);
WIRE 17 -1 (-3600 3975)(-3600 4075);
WIRE 17 -1 (-3600 3975)(-3600 3875);
WIRE 17 -1 (-3600 4700)(-3600 4675);
WIRE 17 -1 (-3600 4700)(-2700 4700);
FORCEPROP 2 LAST SIG_NAME M_B_CPU0_SA_DQS_DP<9:0>
J 0
(-3335 4710);
DISPLAY 0.489362 (-3335 4710);
WIRE 17 -1 (-3600 3525)(-3600 3425);
WIRE 17 -1 (-3600 3625)(-3600 3525);
WIRE 17 -1 (-3600 3425)(-3600 3325);
WIRE 17 -1 (-3600 3325)(-3600 3225);
WIRE 17 -1 (-3600 3650)(-3600 3625);
WIRE 17 -1 (-3600 3650)(-2700 3650);
FORCEPROP 2 LAST SIG_NAME M_B_CPU0_SB_DQS_DP<9:0>
J 0
(-3335 3660);
DISPLAY 0.489362 (-3335 3660);
WIRE 17 -1 (-3400 3475)(-3400 3375);
WIRE 17 -1 (-3400 3575)(-3400 3475);
WIRE 17 -1 (-3400 3375)(-3400 3275);
WIRE 17 -1 (-3400 3275)(-3400 3175);
WIRE 17 -1 (-3400 3600)(-3400 3575);
WIRE 17 -1 (-3400 3600)(-2700 3600);
FORCEPROP 2 LAST SIG_NAME M_B_CPU0_SB_DQS_DN<9:0>
J 0
(-3335 3610);
DISPLAY 0.489362 (-3335 3610);
WIRE 17 -1 (-3600 3125)(-3600 3225);
WIRE 17 -1 (-3600 3025)(-3600 3125);
WIRE 17 -1 (-3600 2925)(-3600 3025);
WIRE 17 -1 (-3400 2775)(-3400 2675);
WIRE 17 -1 (-3400 2875)(-3400 2775);
WIRE 17 -1 (-3400 2875)(-3400 2975);
WIRE 17 -1 (-3400 2975)(-3400 3075);
WIRE 17 -1 (-3400 3075)(-3400 3175);
WIRE 17 -1 (-3600 2825)(-3600 2725);
WIRE 17 -1 (-3600 2925)(-3600 2825);
WIRE 17 -1 (-3400 3925)(-3400 3825);
WIRE 17 -1 (-3400 3825)(-3400 3725);
WIRE 17 -1 (-3600 3875)(-3600 3775);
WIRE 16 -1 (-6650 1225)(-6650 1300);
WIRE 16 -1 (-9050 3150)(-9050 3225);
WIRE 16 -1 (-8550 2525)(-8550 2550);
WIRE 16 -1 (-7700 2925)(-7800 2925);
FORCEPROP 2 LAST SIG_NAME I3C_SPD_DDRB_CPU0_SCL
J 0
(-8185 2935);
DISPLAY 0.446809 (-8185 2935);
FORCEPROP 2 LASTPROP $XRERR UNIQUE?
J 0
(-8425 2935);
DISPLAY 0.638298 (-8425 2935);
PAINT MONO (-8425 2935);
DISPLAY INVISIBLE (-8425 2935);
WIRE 16 -1 (-7800 2925)(-7800 2825);
WIRE 16 -1 (-7800 2825)(-7900 2825);
WIRE 16 -1 (-8100 2825)(-8500 2825);
FORCEPROP 2 LAST SIG_NAME I3C_SPD_DDRAF_CPU0_SCL
J 0
(-8535 2835);
DISPLAY 0.446809 (-8535 2835);
WIRE 16 -1 (-8350 2275)(-8550 2275);
WIRE 16 -1 (-8350 2275)(-8350 2675);
WIRE 16 -1 (-8550 2325)(-8550 2275);
WIRE 16 -1 (-8550 2275)(-8575 2275);
WIRE 16 -1 (-7700 2675)(-8350 2675);
FORCEPROP 2 LAST SIG_NAME PWRGD_CHB_CPU0_DIMM
J 0
(-8275 2685);
DISPLAY 0.489362 (-8275 2685);
FORCEPROP 2 LASTPROP $XRERR UNIQUE?
J 0
(-8515 2685);
DISPLAY 0.638298 (-8515 2685);
PAINT MONO (-8515 2685);
DISPLAY INVISIBLE (-8515 2685);
WIRE 16 -1 (-7700 2975)(-8500 2975);
FORCEPROP 2 LAST SIG_NAME I3C_SPD_DDRAF_CPU0_SDA
J 0
(-8510 2985);
DISPLAY 0.489362 (-8510 2985);
WIRE 16 -1 (-9050 3425)(-9050 3500);
WIRE 16 -1 (-9050 3500)(-8925 3500);
WIRE 16 -1 (-8925 3525)(-8925 3500);
WIRE 16 -1 (-8925 3500)(-8925 3075);
WIRE 16 -1 (-8925 3075)(-7700 3075);
WIRE 16 -1 (-7700 3175)(-8475 3175);
FORCEPROP 2 LAST SIG_NAME M_B_CPU0_ALERT_N
J 0
(-8460 3185);
DISPLAY 0.489362 (-8460 3185);
WIRE 16 -1 (-7700 3025)(-8500 3025);
FORCEPROP 2 LAST SIG_NAME PD_CHB_CPU0_DIMM_SAA
J 0
(-8475 3035);
DISPLAY 0.489362 (-8475 3035);
WIRE 16 -1 (-7700 2575)(-8300 2575);
FORCEPROP 2 LAST SIG_NAME TP_CHB_CPU0_DIMM_RFU_6
J 0
(-8310 2585);
DISPLAY 0.489362 (-8310 2585);
FORCEPROP 2 LASTPROP $XRERR UNIQUE?
J 0
(-8540 2575);
DISPLAY 0.638298 (-8540 2575);
PAINT MONO (-8540 2575);
DISPLAY INVISIBLE (-8540 2575);
WIRE 16 -1 (-7700 2525)(-8300 2525);
FORCEPROP 2 LAST SIG_NAME TP_CHB_CPU0_DIMM_RFU_5
J 0
(-8310 2535);
DISPLAY 0.489362 (-8310 2535);
FORCEPROP 2 LASTPROP $XRERR UNIQUE?
J 0
(-8540 2525);
DISPLAY 0.638298 (-8540 2525);
PAINT MONO (-8540 2525);
DISPLAY INVISIBLE (-8540 2525);
WIRE 16 -1 (-7700 2475)(-8300 2475);
FORCEPROP 2 LAST SIG_NAME TP_CHB_CPU0_DIMM_RFU_4
J 0
(-8310 2485);
DISPLAY 0.489362 (-8310 2485);
FORCEPROP 2 LASTPROP $XRERR UNIQUE?
J 0
(-8540 2475);
DISPLAY 0.638298 (-8540 2475);
PAINT MONO (-8540 2475);
DISPLAY INVISIBLE (-8540 2475);
WIRE 16 -1 (-2250 5775)(-2825 5775);
WIRE 16 -1 (-2250 5775)(-2250 5675);
WIRE 16 -1 (-2250 5775)(-2125 5775);
WIRE 16 -1 (-2825 5675)(-2825 5775);
WIRE 16 -1 (-2825 5775)(-2825 5850);
WIRE 16 -1 (-2125 5225)(-2125 5775);
WIRE 16 -1 (-1825 5225)(-2125 5225);
WIRE 16 -1 (-2125 5175)(-2125 5225);
WIRE 16 -1 (-1825 5175)(-2125 5175);
WIRE 16 -1 (-2125 5125)(-2125 5175);
WIRE 16 -1 (-1825 5125)(-2125 5125);
WIRE 16 -1 (-2250 5350)(-2825 5350);
WIRE 16 -1 (-2250 5350)(-2250 5475);
WIRE 16 -1 (-2825 5350)(-2825 5475);
WIRE 16 -1 (-2825 5350)(-2825 5275);
WIRE 16 -1 (-325 1925)(-325 1875);
WIRE 16 -1 (-325 1975)(-325 1925);
WIRE 16 -1 (-325 1925)(-625 1925);
WIRE 16 -1 (-325 1875)(-325 1700);
WIRE 16 -1 (-325 1875)(-625 1875);
WIRE 16 -1 (-325 2075)(-325 1975);
WIRE 16 -1 (-325 1975)(-625 1975);
WIRE 16 -1 (-325 2125)(-325 2075);
WIRE 16 -1 (-325 2075)(-625 2075);
WIRE 16 -1 (-325 2175)(-325 2125);
WIRE 16 -1 (-325 2125)(-625 2125);
WIRE 16 -1 (-325 2225)(-325 2175);
WIRE 16 -1 (-325 2175)(-625 2175);
WIRE 16 -1 (-325 2275)(-325 2225);
WIRE 16 -1 (-325 2225)(-625 2225);
WIRE 16 -1 (-325 2325)(-325 2275);
WIRE 16 -1 (-325 2275)(-625 2275);
WIRE 16 -1 (-325 2375)(-325 2325);
WIRE 16 -1 (-325 2325)(-625 2325);
WIRE 16 -1 (-325 2425)(-325 2375);
WIRE 16 -1 (-325 2375)(-625 2375);
WIRE 16 -1 (-325 2475)(-325 2425);
WIRE 16 -1 (-325 2425)(-625 2425);
WIRE 16 -1 (-325 2525)(-325 2475);
WIRE 16 -1 (-325 2475)(-625 2475);
WIRE 16 -1 (-325 2575)(-325 2525);
WIRE 16 -1 (-325 2525)(-625 2525);
WIRE 16 -1 (-325 2625)(-325 2575);
WIRE 16 -1 (-325 2575)(-625 2575);
WIRE 16 -1 (-325 2675)(-325 2625);
WIRE 16 -1 (-325 2625)(-625 2625);
WIRE 16 -1 (-325 2725)(-325 2675);
WIRE 16 -1 (-325 2675)(-625 2675);
WIRE 16 -1 (-325 2775)(-325 2725);
WIRE 16 -1 (-325 2725)(-625 2725);
WIRE 16 -1 (-325 2825)(-325 2775);
WIRE 16 -1 (-325 2775)(-625 2775);
WIRE 16 -1 (-325 2875)(-325 2825);
WIRE 16 -1 (-325 2825)(-625 2825);
WIRE 16 -1 (-325 2925)(-325 2875);
WIRE 16 -1 (-325 2875)(-625 2875);
WIRE 16 -1 (-325 2975)(-325 2925);
WIRE 16 -1 (-325 2925)(-625 2925);
WIRE 16 -1 (-325 3025)(-325 2975);
WIRE 16 -1 (-325 2975)(-625 2975);
WIRE 16 -1 (-325 3075)(-325 3025);
WIRE 16 -1 (-325 3025)(-625 3025);
WIRE 16 -1 (-325 3125)(-325 3075);
WIRE 16 -1 (-325 3075)(-625 3075);
WIRE 16 -1 (-325 3175)(-325 3125);
WIRE 16 -1 (-325 3125)(-625 3125);
WIRE 16 -1 (-325 3225)(-325 3175);
WIRE 16 -1 (-325 3175)(-625 3175);
WIRE 16 -1 (-325 3275)(-325 3225);
WIRE 16 -1 (-325 3225)(-625 3225);
WIRE 16 -1 (-325 3325)(-325 3275);
WIRE 16 -1 (-325 3275)(-625 3275);
WIRE 16 -1 (-325 3375)(-325 3325);
WIRE 16 -1 (-325 3325)(-625 3325);
WIRE 16 -1 (-325 3425)(-325 3375);
WIRE 16 -1 (-325 3375)(-625 3375);
WIRE 16 -1 (-325 3475)(-325 3425);
WIRE 16 -1 (-325 3425)(-625 3425);
WIRE 16 -1 (-325 3525)(-325 3475);
WIRE 16 -1 (-325 3475)(-625 3475);
WIRE 16 -1 (-325 3575)(-325 3525);
WIRE 16 -1 (-325 3525)(-625 3525);
WIRE 16 -1 (-325 3625)(-325 3575);
WIRE 16 -1 (-325 3575)(-625 3575);
WIRE 16 -1 (-325 3675)(-325 3625);
WIRE 16 -1 (-325 3625)(-625 3625);
WIRE 16 -1 (-325 3725)(-325 3675);
WIRE 16 -1 (-325 3675)(-625 3675);
WIRE 16 -1 (-325 3775)(-325 3725);
WIRE 16 -1 (-325 3725)(-625 3725);
WIRE 16 -1 (-325 3825)(-325 3775);
WIRE 16 -1 (-325 3775)(-625 3775);
WIRE 16 -1 (-325 3875)(-325 3825);
WIRE 16 -1 (-325 3825)(-625 3825);
WIRE 16 -1 (-325 3925)(-325 3875);
WIRE 16 -1 (-325 3875)(-625 3875);
WIRE 16 -1 (-325 3975)(-325 3925);
WIRE 16 -1 (-325 3925)(-625 3925);
WIRE 16 -1 (-325 4025)(-325 3975);
WIRE 16 -1 (-325 3975)(-625 3975);
WIRE 16 -1 (-325 4075)(-325 4025);
WIRE 16 -1 (-325 4025)(-625 4025);
WIRE 16 -1 (-325 4125)(-325 4075);
WIRE 16 -1 (-325 4075)(-625 4075);
WIRE 16 -1 (-325 4175)(-325 4125);
WIRE 16 -1 (-325 4125)(-625 4125);
WIRE 16 -1 (-325 4225)(-325 4175);
WIRE 16 -1 (-325 4175)(-625 4175);
WIRE 16 -1 (-325 4275)(-325 4225);
WIRE 16 -1 (-325 4225)(-625 4225);
WIRE 16 -1 (-325 4325)(-325 4275);
WIRE 16 -1 (-325 4275)(-625 4275);
WIRE 16 -1 (-325 4375)(-325 4325);
WIRE 16 -1 (-325 4325)(-625 4325);
WIRE 16 -1 (-325 4425)(-325 4375);
WIRE 16 -1 (-325 4375)(-625 4375);
WIRE 16 -1 (-325 4475)(-325 4425);
WIRE 16 -1 (-325 4425)(-625 4425);
WIRE 16 -1 (-325 4525)(-325 4475);
WIRE 16 -1 (-325 4475)(-625 4475);
WIRE 16 -1 (-325 4575)(-325 4525);
WIRE 16 -1 (-325 4525)(-625 4525);
WIRE 16 -1 (-325 4625)(-325 4575);
WIRE 16 -1 (-325 4575)(-625 4575);
WIRE 16 -1 (-325 4675)(-325 4625);
WIRE 16 -1 (-325 4625)(-625 4625);
WIRE 16 -1 (-325 4725)(-325 4675);
WIRE 16 -1 (-325 4675)(-625 4675);
WIRE 16 -1 (-325 4775)(-325 4725);
WIRE 16 -1 (-325 4725)(-625 4725);
WIRE 16 -1 (-325 4825)(-325 4775);
WIRE 16 -1 (-325 4775)(-625 4775);
WIRE 16 -1 (-325 4875)(-325 4825);
WIRE 16 -1 (-325 4825)(-625 4825);
WIRE 16 -1 (-325 4925)(-325 4875);
WIRE 16 -1 (-325 4875)(-625 4875);
WIRE 16 -1 (-325 4975)(-325 4925);
WIRE 16 -1 (-325 4925)(-625 4925);
WIRE 16 -1 (-325 5025)(-325 4975);
WIRE 16 -1 (-325 4975)(-625 4975);
WIRE 16 -1 (-325 5075)(-325 5025);
WIRE 16 -1 (-325 5025)(-625 5025);
WIRE 16 -1 (-325 5125)(-325 5075);
WIRE 16 -1 (-325 5075)(-625 5075);
WIRE 16 -1 (-325 5175)(-325 5125);
WIRE 16 -1 (-325 5125)(-625 5125);
WIRE 16 -1 (-325 5225)(-325 5175);
WIRE 16 -1 (-325 5175)(-625 5175);
WIRE 16 -1 (-325 5225)(-625 5225);
WIRE 16 -1 (-1825 1975)(-2125 1975);
WIRE 16 -1 (-2125 2025)(-2125 1975);
WIRE 16 -1 (-2125 1975)(-2125 1875);
WIRE 16 -1 (-1825 2025)(-2125 2025);
WIRE 16 -1 (-2125 2075)(-2125 2025);
WIRE 16 -1 (-1825 2075)(-2125 2075);
WIRE 16 -1 (-2125 2125)(-2125 2075);
WIRE 16 -1 (-1825 2125)(-2125 2125);
WIRE 16 -1 (-2125 2175)(-2125 2125);
WIRE 16 -1 (-1825 2175)(-2125 2175);
WIRE 16 -1 (-2125 2225)(-2125 2175);
WIRE 16 -1 (-1825 2225)(-2125 2225);
WIRE 16 -1 (-2125 2275)(-2125 2225);
WIRE 16 -1 (-1825 2275)(-2125 2275);
WIRE 16 -1 (-2125 2325)(-2125 2275);
WIRE 16 -1 (-1825 2325)(-2125 2325);
WIRE 16 -1 (-2125 2375)(-2125 2325);
WIRE 16 -1 (-1825 2375)(-2125 2375);
WIRE 16 -1 (-2125 2425)(-2125 2375);
WIRE 16 -1 (-1825 2425)(-2125 2425);
WIRE 16 -1 (-2125 2475)(-2125 2425);
WIRE 16 -1 (-1825 2475)(-2125 2475);
WIRE 16 -1 (-2125 2525)(-2125 2475);
WIRE 16 -1 (-1825 2525)(-2125 2525);
WIRE 16 -1 (-2125 2575)(-2125 2525);
WIRE 16 -1 (-1825 2575)(-2125 2575);
WIRE 16 -1 (-2125 2625)(-2125 2575);
WIRE 16 -1 (-1825 2625)(-2125 2625);
WIRE 16 -1 (-2125 2675)(-2125 2625);
WIRE 16 -1 (-1825 2675)(-2125 2675);
WIRE 16 -1 (-2125 2725)(-2125 2675);
WIRE 16 -1 (-1825 2725)(-2125 2725);
WIRE 16 -1 (-2125 2775)(-2125 2725);
WIRE 16 -1 (-1825 2775)(-2125 2775);
WIRE 16 -1 (-2125 2825)(-2125 2775);
WIRE 16 -1 (-1825 2825)(-2125 2825);
WIRE 16 -1 (-2125 2875)(-2125 2825);
WIRE 16 -1 (-1825 2875)(-2125 2875);
WIRE 16 -1 (-2125 2925)(-2125 2875);
WIRE 16 -1 (-1825 2925)(-2125 2925);
WIRE 16 -1 (-2125 2975)(-2125 2925);
WIRE 16 -1 (-1825 2975)(-2125 2975);
WIRE 16 -1 (-2125 3025)(-2125 2975);
WIRE 16 -1 (-1825 3025)(-2125 3025);
WIRE 16 -1 (-2125 3075)(-2125 3025);
WIRE 16 -1 (-1825 3075)(-2125 3075);
WIRE 16 -1 (-2125 3125)(-2125 3075);
WIRE 16 -1 (-1825 3125)(-2125 3125);
WIRE 16 -1 (-2125 3175)(-2125 3125);
WIRE 16 -1 (-1825 3175)(-2125 3175);
WIRE 16 -1 (-2125 3225)(-2125 3175);
WIRE 16 -1 (-1825 3225)(-2125 3225);
WIRE 16 -1 (-2125 3275)(-2125 3225);
WIRE 16 -1 (-1825 3275)(-2125 3275);
WIRE 16 -1 (-2125 3325)(-2125 3275);
WIRE 16 -1 (-1825 3325)(-2125 3325);
WIRE 16 -1 (-2125 3375)(-2125 3325);
WIRE 16 -1 (-1825 3375)(-2125 3375);
WIRE 16 -1 (-2125 3425)(-2125 3375);
WIRE 16 -1 (-1825 3425)(-2125 3425);
WIRE 16 -1 (-2125 3475)(-2125 3425);
WIRE 16 -1 (-1825 3475)(-2125 3475);
WIRE 16 -1 (-2125 3525)(-2125 3475);
WIRE 16 -1 (-1825 3525)(-2125 3525);
WIRE 16 -1 (-2125 3575)(-2125 3525);
WIRE 16 -1 (-1825 3575)(-2125 3575);
WIRE 16 -1 (-2125 3625)(-2125 3575);
WIRE 16 -1 (-1825 3625)(-2125 3625);
WIRE 16 -1 (-2125 3675)(-2125 3625);
WIRE 16 -1 (-1825 3675)(-2125 3675);
WIRE 16 -1 (-2125 3725)(-2125 3675);
WIRE 16 -1 (-1825 3725)(-2125 3725);
WIRE 16 -1 (-2125 3775)(-2125 3725);
WIRE 16 -1 (-1825 3775)(-2125 3775);
WIRE 16 -1 (-2125 3825)(-2125 3775);
WIRE 16 -1 (-1825 3825)(-2125 3825);
WIRE 16 -1 (-2125 3875)(-2125 3825);
WIRE 16 -1 (-1825 3875)(-2125 3875);
WIRE 16 -1 (-2125 3925)(-2125 3875);
WIRE 16 -1 (-1825 3925)(-2125 3925);
WIRE 16 -1 (-2125 3975)(-2125 3925);
WIRE 16 -1 (-1825 3975)(-2125 3975);
WIRE 16 -1 (-2125 4025)(-2125 3975);
WIRE 16 -1 (-1825 4025)(-2125 4025);
WIRE 16 -1 (-2125 4075)(-2125 4025);
WIRE 16 -1 (-2125 4125)(-2125 4075);
WIRE 16 -1 (-1825 4075)(-2125 4075);
WIRE 16 -1 (-1825 4125)(-2125 4125);
WIRE 16 -1 (-2125 4175)(-2125 4125);
WIRE 16 -1 (-1825 4175)(-2125 4175);
WIRE 16 -1 (-2125 4225)(-2125 4175);
WIRE 16 -1 (-1825 4225)(-2125 4225);
WIRE 16 -1 (-2125 4275)(-2125 4225);
WIRE 16 -1 (-1825 4275)(-2125 4275);
WIRE 16 -1 (-2125 4325)(-2125 4275);
WIRE 16 -1 (-1825 4325)(-2125 4325);
WIRE 16 -1 (-2125 4375)(-2125 4325);
WIRE 16 -1 (-1825 4375)(-2125 4375);
WIRE 16 -1 (-2125 4425)(-2125 4375);
WIRE 16 -1 (-1825 4425)(-2125 4425);
WIRE 16 -1 (-2125 4475)(-2125 4425);
WIRE 16 -1 (-1825 4475)(-2125 4475);
WIRE 16 -1 (-2125 4525)(-2125 4475);
WIRE 16 -1 (-1825 4525)(-2125 4525);
WIRE 16 -1 (-2125 4575)(-2125 4525);
WIRE 16 -1 (-1825 4575)(-2125 4575);
WIRE 16 -1 (-2125 4625)(-2125 4575);
WIRE 16 -1 (-1825 4625)(-2125 4625);
WIRE 16 -1 (-2125 4675)(-2125 4625);
WIRE 16 -1 (-1825 4675)(-2125 4675);
WIRE 16 -1 (-2125 4725)(-2125 4675);
WIRE 16 -1 (-1825 4725)(-2125 4725);
WIRE 16 -1 (-2125 4775)(-2125 4725);
WIRE 16 -1 (-1825 4775)(-2125 4775);
WIRE 16 -1 (-2125 4825)(-2125 4775);
WIRE 16 -1 (-1825 4825)(-2125 4825);
WIRE 16 -1 (-2125 4875)(-2125 4825);
WIRE 16 -1 (-1825 4875)(-2125 4875);
WIRE 16 -1 (-2125 4925)(-2125 4875);
WIRE 16 -1 (-1825 4925)(-2125 4925);
WIRE 16 -1 (-2125 4975)(-2125 4925);
WIRE 16 -1 (-1825 4975)(-2125 4975);
WIRE 16 -1 (-2125 5025)(-2125 4975);
WIRE 16 -1 (-1825 5025)(-2125 5025);
WIRE 16 -1 (-2125 5075)(-2125 5025);
WIRE 16 -1 (-1825 5075)(-2125 5075);
WIRE 16 -1 (-7700 2425)(-8300 2425);
FORCEPROP 2 LAST SIG_NAME TP_CHB_CPU0_DIMM_RFU_3
J 0
(-8310 2435);
DISPLAY 0.489362 (-8310 2435);
FORCEPROP 2 LASTPROP $XRERR UNIQUE?
J 0
(-8540 2425);
DISPLAY 0.638298 (-8540 2425);
PAINT MONO (-8540 2425);
DISPLAY INVISIBLE (-8540 2425);
WIRE 16 -1 (-7700 2275)(-8300 2275);
FORCEPROP 2 LAST SIG_NAME TP_CHB_CPU0_DIMM_RFU_0
J 0
(-8310 2285);
DISPLAY 0.489362 (-8310 2285);
FORCEPROP 2 LASTPROP $XRERR UNIQUE?
J 0
(-8540 2275);
DISPLAY 0.638298 (-8540 2275);
PAINT MONO (-8540 2275);
DISPLAY INVISIBLE (-8540 2275);
WIRE 16 -1 (-7700 2325)(-8300 2325);
FORCEPROP 2 LAST SIG_NAME TP_CHB_CPU0_DIMM_RFU_1
J 0
(-8310 2335);
DISPLAY 0.489362 (-8310 2335);
FORCEPROP 2 LASTPROP $XRERR UNIQUE?
J 0
(-8540 2325);
DISPLAY 0.638298 (-8540 2325);
PAINT MONO (-8540 2325);
DISPLAY INVISIBLE (-8540 2325);
WIRE 16 -1 (-7700 2375)(-8300 2375);
FORCEPROP 2 LAST SIG_NAME TP_CHB_CPU0_DIMM_RFU_2
J 0
(-8310 2385);
DISPLAY 0.489362 (-8310 2385);
FORCEPROP 2 LASTPROP $XRERR UNIQUE?
J 0
(-8540 2375);
DISPLAY 0.638298 (-8540 2375);
PAINT MONO (-8540 2375);
DISPLAY INVISIBLE (-8540 2375);
WIRE 16 -1 (-7700 3225)(-8475 3225);
FORCEPROP 2 LAST SIG_NAME M_B_CPU0_RESET_N
J 0
(-8460 3235);
DISPLAY 0.489362 (-8460 3235);
WIRE 16 -1 (-7700 3475)(-7900 3475);
WIRE 16 -1 (-7700 3325)(-7900 3325);
WIRE 16 -1 (-7700 3375)(-7900 3375);
WIRE 16 -1 (-7700 3425)(-7900 3425);
WIRE 16 -1 (-6300 3525)(-6500 3525);
WIRE 16 -1 (-6300 3825)(-6500 3825);
WIRE 16 -1 (-7700 4275)(-8500 4275);
FORCEPROP 2 LAST SIG_NAME M_B_CPU0_CLK_DP<0>
J 0
(-8450 4285);
DISPLAY 0.489362 (-8450 4285);
WIRE 16 -1 (-7700 4375)(-8500 4375);
FORCEPROP 2 LAST SIG_NAME M_B_CPU0_SB_CS_N<0>
J 0
(-8450 4385);
DISPLAY 0.489362 (-8450 4385);
WIRE 16 -1 (-7700 4725)(-8500 4725);
FORCEPROP 2 LAST SIG_NAME M_B_CPU0_SA_PAR
J 0
(-8450 4735);
DISPLAY 0.489362 (-8450 4735);
WIRE 16 -1 (-7700 4675)(-8500 4675);
FORCEPROP 2 LAST SIG_NAME M_B_CPU0_SB_PAR
J 0
(-8450 4685);
DISPLAY 0.489362 (-8450 4685);
WIRE 16 -1 (-6300 5275)(-6500 5275);
WIRE 16 -1 (-6300 5225)(-6500 5225);
WIRE 16 -1 (-3850 3600)(-3700 3600);
WIRE 16 -1 (-3500 3550)(-3850 3550);
WIRE 16 -1 (-3850 3700)(-3500 3700);
WIRE 16 -1 (-3700 3750)(-3850 3750);
WIRE 16 -1 (-3850 4650)(-3700 4650);
WIRE 16 -1 (-3500 4600)(-3850 4600);
WIRE 16 -1 (-3700 4550)(-3850 4550);
WIRE 16 -1 (-3500 4500)(-3850 4500);
WIRE 16 -1 (-3500 3350)(-3850 3350);
WIRE 16 -1 (-3700 4450)(-3850 4450);
WIRE 16 -1 (-3700 3300)(-3850 3300);
WIRE 16 -1 (-3500 3250)(-3850 3250);
WIRE 16 -1 (-3500 4300)(-3850 4300);
WIRE 16 -1 (-3850 3200)(-3700 3200);
WIRE 16 -1 (-3500 3150)(-3850 3150);
WIRE 16 -1 (-3850 4250)(-3700 4250);
WIRE 16 -1 (-3500 4200)(-3850 4200);
WIRE 16 -1 (-3700 3100)(-3850 3100);
WIRE 16 -1 (-3500 3050)(-3850 3050);
WIRE 16 -1 (-3700 4150)(-3850 4150);
WIRE 16 -1 (-3500 4100)(-3850 4100);
WIRE 16 -1 (-3700 3000)(-3850 3000);
WIRE 16 -1 (-3500 2950)(-3850 2950);
WIRE 16 -1 (-3700 4050)(-3850 4050);
WIRE 16 -1 (-3500 4000)(-3850 4000);
WIRE 16 -1 (-3700 2900)(-3850 2900);
WIRE 16 -1 (-3500 2850)(-3850 2850);
WIRE 16 -1 (-3700 3950)(-3850 3950);
WIRE 16 -1 (-3500 3900)(-3850 3900);
WIRE 16 -1 (-3850 2800)(-3700 2800);
WIRE 16 -1 (-3500 2750)(-3850 2750);
WIRE 16 -1 (-3850 3850)(-3700 3850);
WIRE 16 -1 (-3500 3800)(-3850 3800);
WIRE 16 -1 (-3700 2700)(-3850 2700);
WIRE 16 -1 (-3850 2650)(-3500 2650);
WIRE 16 -1 (-3700 3400)(-3850 3400);
WIRE 16 -1 (-3500 3450)(-3850 3450);
WIRE 16 -1 (-3700 3500)(-3850 3500);
WIRE 16 -1 (-3700 4350)(-3850 4350);
WIRE 16 -1 (-3500 4400)(-3850 4400);
WIRE 16 -1 (-6500 5325)(-6300 5325);
WIRE 16 -1 (-6300 5375)(-6500 5375);
WIRE 16 -1 (-7700 5525)(-7900 5525);
WIRE 16 -1 (-6500 4925)(-6300 4925);
WIRE 16 -1 (-6300 4875)(-6500 4875);
WIRE 16 -1 (-7700 2075)(-8500 2075);
FORCEPROP 2 LAST SIG_NAME M_B_CPU0_SB_RSP<0>
J 0
(-8450 2085);
DISPLAY 0.489362 (-8450 2085);
WIRE 16 -1 (-7700 2125)(-8500 2125);
FORCEPROP 2 LAST SIG_NAME M_B_CPU0_SA_RSP<0>
J 0
(-8450 2135);
DISPLAY 0.489362 (-8450 2135);
WIRE 16 -1 (-6300 2325)(-6500 2325);
WIRE 16 -1 (-6300 2375)(-6500 2375);
WIRE 16 -1 (-6300 2425)(-6500 2425);
WIRE 16 -1 (-6500 2475)(-6300 2475);
WIRE 16 -1 (-6300 2525)(-6500 2525);
WIRE 16 -1 (-6300 2575)(-6500 2575);
WIRE 16 -1 (-6300 2625)(-6500 2625);
WIRE 16 -1 (-6500 2675)(-6300 2675);
WIRE 16 -1 (-6300 2725)(-6500 2725);
WIRE 16 -1 (-6300 2775)(-6500 2775);
WIRE 16 -1 (-6300 2825)(-6500 2825);
WIRE 16 -1 (-6500 2875)(-6300 2875);
WIRE 16 -1 (-6300 2925)(-6500 2925);
WIRE 16 -1 (-6300 2975)(-6500 2975);
WIRE 16 -1 (-6300 3025)(-6500 3025);
WIRE 16 -1 (-6500 3075)(-6300 3075);
WIRE 16 -1 (-6300 3125)(-6500 3125);
WIRE 16 -1 (-6300 3175)(-6500 3175);
WIRE 16 -1 (-6300 3225)(-6500 3225);
WIRE 16 -1 (-6500 3275)(-6300 3275);
WIRE 16 -1 (-6300 3325)(-6500 3325);
WIRE 16 -1 (-6300 3375)(-6500 3375);
WIRE 16 -1 (-6300 3425)(-6500 3425);
WIRE 16 -1 (-6500 3475)(-6300 3475);
WIRE 16 -1 (-6300 3575)(-6500 3575);
WIRE 16 -1 (-6300 3625)(-6500 3625);
WIRE 16 -1 (-6500 3675)(-6300 3675);
WIRE 16 -1 (-6300 3725)(-6500 3725);
WIRE 16 -1 (-6300 3775)(-6500 3775);
WIRE 16 -1 (-6500 3875)(-6300 3875);
WIRE 16 -1 (-6300 3975)(-6500 3975);
WIRE 16 -1 (-6300 4025)(-6500 4025);
WIRE 16 -1 (-6300 4075)(-6500 4075);
WIRE 16 -1 (-6500 4125)(-6300 4125);
WIRE 16 -1 (-6300 4175)(-6500 4175);
WIRE 16 -1 (-6300 4225)(-6500 4225);
WIRE 16 -1 (-6300 4275)(-6500 4275);
WIRE 16 -1 (-6500 4325)(-6300 4325);
WIRE 16 -1 (-6300 4375)(-6500 4375);
WIRE 16 -1 (-6300 4425)(-6500 4425);
WIRE 16 -1 (-6300 4475)(-6500 4475);
WIRE 16 -1 (-6500 4525)(-6300 4525);
WIRE 16 -1 (-6300 4575)(-6500 4575);
WIRE 16 -1 (-6300 4625)(-6500 4625);
WIRE 16 -1 (-6300 4675)(-6500 4675);
WIRE 16 -1 (-6500 4725)(-6300 4725);
WIRE 16 -1 (-6300 4775)(-6500 4775);
WIRE 16 -1 (-6300 4825)(-6500 4825);
WIRE 16 -1 (-6300 4975)(-6500 4975);
WIRE 16 -1 (-6300 5025)(-6500 5025);
WIRE 16 -1 (-6300 5075)(-6500 5075);
WIRE 16 -1 (-6500 5125)(-6300 5125);
WIRE 16 -1 (-6300 5175)(-6500 5175);
WIRE 16 -1 (-6300 5425)(-6500 5425);
WIRE 16 -1 (-6300 5475)(-6500 5475);
WIRE 16 -1 (-7700 4425)(-8500 4425);
FORCEPROP 2 LAST SIG_NAME M_B_CPU0_SB_CS_N<1>
J 0
(-8450 4435);
DISPLAY 0.489362 (-8450 4435);
WIRE 16 -1 (-7700 4575)(-8500 4575);
FORCEPROP 2 LAST SIG_NAME M_B_CPU0_SA_CS_N<1>
J 0
(-8450 4585);
DISPLAY 0.489362 (-8450 4585);
WIRE 16 -1 (-7700 4525)(-8500 4525);
FORCEPROP 2 LAST SIG_NAME M_B_CPU0_SA_CS_N<0>
J 0
(-8450 4535);
DISPLAY 0.489362 (-8450 4535);
WIRE 16 -1 (-7700 4225)(-8500 4225);
FORCEPROP 2 LAST SIG_NAME M_B_CPU0_CLK_DN<0>
J 0
(-8450 4235);
DISPLAY 0.489362 (-8450 4235);
WIRE 16 -1 (-7700 3525)(-7900 3525);
WIRE 16 -1 (-7700 3575)(-7900 3575);
WIRE 16 -1 (-7700 3625)(-7900 3625);
WIRE 16 -1 (-7700 3775)(-7900 3775);
WIRE 16 -1 (-7700 3875)(-7900 3875);
WIRE 16 -1 (-7700 3925)(-7900 3925);
WIRE 16 -1 (-7700 4025)(-7900 4025);
WIRE 16 -1 (-7700 4075)(-7900 4075);
WIRE 16 -1 (-7700 5125)(-7900 5125);
WIRE 16 -1 (-7700 5075)(-7900 5075);
WIRE 16 -1 (-7700 5475)(-7900 5475);
WIRE 16 -1 (-7700 5025)(-7900 5025);
WIRE 16 -1 (-7700 5425)(-7900 5425);
WIRE 16 -1 (-7700 4975)(-7900 4975);
WIRE 16 -1 (-7700 5375)(-7900 5375);
WIRE 16 -1 (-7700 4925)(-7900 4925);
WIRE 16 -1 (-7700 5325)(-7900 5325);
WIRE 16 -1 (-7700 4875)(-7900 4875);
WIRE 16 -1 (-7700 5275)(-7900 5275);
WIRE 16 -1 (-7700 4825)(-7900 4825);
WIRE 16 -1 (-7700 5225)(-7900 5225);
WIRE 16 -1 (-7700 3675)(-7900 3675);
WIRE 16 -1 (-7700 3825)(-7900 3825);
WIRE 16 -1 (-7700 3975)(-7900 3975);
WIRE 16 -1 (-7700 4125)(-7900 4125);
WIRE 16 -1 (-6500 5525)(-6300 5525);
WIRE 16 -1 (-9125 2275)(-8775 2275);
FORCEPROP 2 LAST SIG_NAME PWRGD_CHAF_CPU0
J 0
(-9135 2285);
DISPLAY 0.489362 (-9135 2285);
WIRE 16 -1 (-6650 1575)(-6650 1500);
WIRE 16 -1 (-6650 1575)(-7375 1575);
FORCEPROP 2 LAST SIG_NAME PD_CHB_CPU0_DIMM_SAA
J 0
(-7360 1585);
DISPLAY 0.489362 (-7360 1585);
DOT 1 (-2825 5775);
DOT 1 (-2125 5175);
DOT 1 (-8550 2275);
DOT 1 (-8925 3500);
DOT 1 (-2125 5225);
DOT 1 (-2125 2475);
DOT 1 (-2125 4575);
DOT 1 (-2125 3025);
DOT 1 (-2125 2425);
DOT 1 (-2125 1975);
DOT 1 (-2125 2025);
DOT 1 (-2125 2075);
DOT 1 (-2125 2175);
DOT 1 (-2125 2125);
DOT 1 (-2125 2225);
DOT 1 (-2125 2275);
DOT 1 (-2125 2325);
DOT 1 (-2125 2375);
DOT 1 (-2125 2775);
DOT 1 (-2125 2875);
DOT 1 (-2125 2925);
DOT 1 (-2125 2975);
DOT 1 (-2125 3075);
DOT 1 (-2125 3125);
DOT 1 (-2125 3175);
DOT 1 (-2125 3225);
DOT 1 (-2125 3375);
DOT 1 (-2125 3325);
DOT 1 (-2125 3275);
DOT 1 (-2125 3525);
DOT 1 (-2125 3575);
DOT 1 (-2125 3625);
DOT 1 (-2125 3725);
DOT 1 (-2125 3675);
DOT 1 (-2125 3775);
DOT 1 (-2125 3825);
DOT 1 (-2125 3875);
DOT 1 (-2125 3925);
DOT 1 (-2125 4025);
DOT 1 (-2125 4075);
DOT 1 (-2125 4125);
DOT 1 (-2125 4175);
DOT 1 (-325 1875);
DOT 1 (-325 1925);
DOT 1 (-325 1975);
DOT 1 (-325 2075);
DOT 1 (-325 2125);
DOT 1 (-325 2175);
DOT 1 (-325 2225);
DOT 1 (-325 2275);
DOT 1 (-325 2325);
DOT 1 (-325 2375);
DOT 1 (-325 2425);
DOT 1 (-325 2475);
DOT 1 (-325 2575);
DOT 1 (-325 2525);
DOT 1 (-325 2625);
DOT 1 (-325 2675);
DOT 1 (-325 2725);
DOT 1 (-325 2825);
DOT 1 (-325 2775);
DOT 1 (-325 2875);
DOT 1 (-325 2925);
DOT 1 (-325 2975);
DOT 1 (-325 3075);
DOT 1 (-325 3025);
DOT 1 (-325 3125);
DOT 1 (-325 3175);
DOT 1 (-325 3225);
DOT 1 (-325 3325);
DOT 1 (-325 3375);
DOT 1 (-325 3275);
DOT 1 (-325 3475);
DOT 1 (-325 3425);
DOT 1 (-325 3525);
DOT 1 (-325 3575);
DOT 1 (-325 3625);
DOT 1 (-325 3725);
DOT 1 (-325 3675);
DOT 1 (-325 3775);
DOT 1 (-325 3825);
DOT 1 (-325 3875);
DOT 1 (-325 3975);
DOT 1 (-325 3925);
DOT 1 (-325 4025);
DOT 1 (-325 4075);
DOT 1 (-325 4125);
DOT 1 (-325 4225);
DOT 1 (-325 4175);
DOT 1 (-325 4275);
DOT 1 (-2125 4525);
DOT 1 (-2125 4725);
DOT 1 (-2125 4775);
DOT 1 (-325 4325);
DOT 1 (-325 4375);
DOT 1 (-325 4425);
DOT 1 (-325 4475);
DOT 1 (-325 4525);
DOT 1 (-325 4625);
DOT 1 (-325 4575);
DOT 1 (-325 4675);
DOT 1 (-325 4725);
DOT 1 (-325 4775);
DOT 1 (-325 4875);
DOT 1 (-325 4825);
DOT 1 (-325 4975);
DOT 1 (-325 4925);
DOT 1 (-325 5025);
DOT 1 (-325 5125);
DOT 1 (-325 5075);
DOT 1 (-325 5175);
DOT 1 (-2125 3425);
DOT 1 (-2125 3475);
DOT 1 (-2125 4225);
DOT 1 (-2125 4275);
DOT 1 (-2125 4325);
DOT 1 (-2125 4375);
DOT 1 (-2125 4425);
DOT 1 (-2125 4475);
DOT 1 (-2125 4625);
DOT 1 (-2125 4675);
DOT 1 (-2125 4825);
DOT 1 (-2125 4875);
DOT 1 (-2125 4925);
DOT 1 (-2125 4975);
DOT 1 (-2125 5025);
DOT 1 (-2125 2525);
DOT 1 (-2125 2575);
DOT 1 (-2125 2625);
DOT 1 (-2125 2675);
DOT 1 (-2125 2725);
DOT 1 (-2125 2825);
DOT 1 (-2125 3975);
DOT 1 (-2825 5350);
DOT 1 (-2250 5775);
QUIT
